FILE_TYPE = MACRO_DRAWING;
SET COLOR_WIRE YELLOW;
SET COLOR_PROP ORANGE;
SET COLOR_DOT WHITE;
SET COLOR_ARC YELLOW;
SET COLOR_BODY GREEN;
SET COLOR_NOTE PURPLE;
SET PROP_DISPLAY VALUE;
SET PAGE_NUMBER P67;
FORCEADD Q_CAP..1
(-10425 5850);
FORCEPROP 1 LAST LOCATION C2154
J 0
(-10375 5950);
DISPLAY 0.489362 (-10375 5950);
PAINT SKYBLUE (-10375 5950);
FORCEPROP 2 LAST $SEC 1
J 0
(-10375 6050);
DISPLAY 0.680851 (-10375 6050);
PAINT MONO (-10375 6050);
DISPLAY INVISIBLE (-10375 6050);
FORCEPROP 2 LAST CDS_SEC 1
J 0
(-10375 6050);
DISPLAY 1.021277 (-10375 6050);
DISPLAY INVISIBLE (-10375 6050);
FORCEPROP 1 LASTPIN (-10425 5950) $PN 1
J 0
(-10415 5930);
DISPLAY 0.489362 (-10415 5930);
FORCEPROP 1 LASTPIN (-10425 5750) $PN 2
J 0
(-10415 5730);
DISPLAY 0.489362 (-10415 5730);
FORCEPROP 1 LAST MATERIAL X6S
J 0
(-10375 5750);
DISPLAY 0.489362 (-10375 5750);
PAINT SKYBLUE (-10375 5750);
FORCEPROP 1 LAST TOLERANCE 20%
J 0
(-10375 5800);
DISPLAY 0.489362 (-10375 5800);
PAINT SKYBLUE (-10375 5800);
FORCEPROP 1 LAST VALUE 22UF
J 0
(-10375 5900);
DISPLAY 0.489362 (-10375 5900);
PAINT SKYBLUE (-10375 5900);
FORCEPROP 1 LAST PART_NUMBER CH622KMEB02
J 0
(-10375 5700);
DISPLAY 0.489362 (-10375 5700);
PAINT SKYBLUE (-10375 5700);
FORCEPROP 1 LAST VOLTAGE 4V
J 0
(-10375 5850);
DISPLAY 0.489362 (-10375 5850);
PAINT SKYBLUE (-10375 5850);
FORCEPROP 1 LAST PACK_TYPE C0402
J 0
(-10375 5650);
DISPLAY 0.489362 (-10375 5650);
PAINT SKYBLUE (-10375 5650);
FORCEPROP 2 LAST CDS_LIB pure_quanta
J 0
(-10425 5850);
PAINT MONO (-10425 5850);
DISPLAY INVISIBLE (-10425 5850);
FORCEPROP 1 LAST PATH I100
J 0
(-10375 6000);
DISPLAY 0.978723 (-10375 6000);
PAINT WHITE (-10375 6000);
DISPLAY INVISIBLE (-10375 6000);
FORCEADD Q_CAP..1
(-9975 5050);
FORCEPROP 1 LAST LOCATION C3894
J 0
(-9925 5150);
DISPLAY 0.489362 (-9925 5150);
PAINT SKYBLUE (-9925 5150);
FORCEPROP 2 LAST $SEC 1
J 0
(-9925 5250);
DISPLAY 0.680851 (-9925 5250);
PAINT MONO (-9925 5250);
DISPLAY INVISIBLE (-9925 5250);
FORCEPROP 2 LAST CDS_SEC 1
J 0
(-9925 5250);
DISPLAY 1.021277 (-9925 5250);
DISPLAY INVISIBLE (-9925 5250);
FORCEPROP 1 LASTPIN (-9975 5150) $PN 1
J 0
(-9965 5130);
DISPLAY 0.489362 (-9965 5130);
FORCEPROP 1 LASTPIN (-9975 4950) $PN 2
J 0
(-9965 4930);
DISPLAY 0.489362 (-9965 4930);
FORCEPROP 1 LAST MATERIAL X6S
J 0
(-9925 4950);
DISPLAY 0.489362 (-9925 4950);
PAINT SKYBLUE (-9925 4950);
FORCEPROP 1 LAST TOLERANCE 20%
J 0
(-9925 5000);
DISPLAY 0.489362 (-9925 5000);
PAINT SKYBLUE (-9925 5000);
FORCEPROP 1 LAST VALUE 22UF
J 0
(-9925 5100);
DISPLAY 0.489362 (-9925 5100);
PAINT SKYBLUE (-9925 5100);
FORCEPROP 1 LAST PART_NUMBER CH622KMEB02
J 0
(-9925 4900);
DISPLAY 0.489362 (-9925 4900);
PAINT SKYBLUE (-9925 4900);
FORCEPROP 1 LAST VOLTAGE 4V
J 0
(-9925 5050);
DISPLAY 0.489362 (-9925 5050);
PAINT SKYBLUE (-9925 5050);
FORCEPROP 1 LAST PACK_TYPE C0402
J 0
(-9925 4850);
DISPLAY 0.489362 (-9925 4850);
PAINT SKYBLUE (-9925 4850);
FORCEPROP 2 LAST CDS_LIB pure_quanta
J 0
(-9975 5050);
PAINT MONO (-9975 5050);
DISPLAY INVISIBLE (-9975 5050);
FORCEPROP 1 LAST PATH I101
J 0
(-9925 5200);
DISPLAY 0.978723 (-9925 5200);
PAINT WHITE (-9925 5200);
DISPLAY INVISIBLE (-9925 5200);
FORCEADD Q_CAP..1
(-9525 5050);
FORCEPROP 1 LAST LOCATION C3895
J 0
(-9475 5150);
DISPLAY 0.489362 (-9475 5150);
PAINT SKYBLUE (-9475 5150);
FORCEPROP 2 LAST $SEC 1
J 0
(-9475 5250);
DISPLAY 0.680851 (-9475 5250);
PAINT MONO (-9475 5250);
DISPLAY INVISIBLE (-9475 5250);
FORCEPROP 2 LAST CDS_SEC 1
J 0
(-9475 5250);
DISPLAY 1.021277 (-9475 5250);
DISPLAY INVISIBLE (-9475 5250);
FORCEPROP 1 LASTPIN (-9525 5150) $PN 1
J 0
(-9515 5130);
DISPLAY 0.489362 (-9515 5130);
FORCEPROP 1 LASTPIN (-9525 4950) $PN 2
J 0
(-9515 4930);
DISPLAY 0.489362 (-9515 4930);
FORCEPROP 1 LAST MATERIAL X6S
J 0
(-9475 4950);
DISPLAY 0.489362 (-9475 4950);
PAINT SKYBLUE (-9475 4950);
FORCEPROP 1 LAST TOLERANCE 20%
J 0
(-9475 5000);
DISPLAY 0.489362 (-9475 5000);
PAINT SKYBLUE (-9475 5000);
FORCEPROP 1 LAST VALUE 22UF
J 0
(-9475 5100);
DISPLAY 0.489362 (-9475 5100);
PAINT SKYBLUE (-9475 5100);
FORCEPROP 1 LAST PART_NUMBER CH622KMEB02
J 0
(-9475 4900);
DISPLAY 0.489362 (-9475 4900);
PAINT SKYBLUE (-9475 4900);
FORCEPROP 1 LAST VOLTAGE 4V
J 0
(-9475 5050);
DISPLAY 0.489362 (-9475 5050);
PAINT SKYBLUE (-9475 5050);
FORCEPROP 1 LAST PACK_TYPE C0402
J 0
(-9475 4850);
DISPLAY 0.489362 (-9475 4850);
PAINT SKYBLUE (-9475 4850);
FORCEPROP 2 LAST CDS_LIB pure_quanta
J 0
(-9525 5050);
PAINT MONO (-9525 5050);
DISPLAY INVISIBLE (-9525 5050);
FORCEPROP 1 LAST PATH I102
J 0
(-9475 5200);
DISPLAY 0.978723 (-9475 5200);
PAINT WHITE (-9475 5200);
DISPLAY INVISIBLE (-9475 5200);
FORCEADD Q_CAP..1
(-9975 5850);
FORCEPROP 1 LAST LOCATION C2157
J 0
(-9925 5950);
DISPLAY 0.489362 (-9925 5950);
PAINT SKYBLUE (-9925 5950);
FORCEPROP 2 LAST $SEC 1
J 0
(-9925 6050);
DISPLAY 0.680851 (-9925 6050);
PAINT MONO (-9925 6050);
DISPLAY INVISIBLE (-9925 6050);
FORCEPROP 2 LAST CDS_SEC 1
J 0
(-9925 6050);
DISPLAY 1.021277 (-9925 6050);
DISPLAY INVISIBLE (-9925 6050);
FORCEPROP 1 LASTPIN (-9975 5950) $PN 1
J 0
(-9965 5930);
DISPLAY 0.489362 (-9965 5930);
FORCEPROP 1 LASTPIN (-9975 5750) $PN 2
J 0
(-9965 5730);
DISPLAY 0.489362 (-9965 5730);
FORCEPROP 1 LAST MATERIAL X6S
J 0
(-9925 5750);
DISPLAY 0.489362 (-9925 5750);
PAINT SKYBLUE (-9925 5750);
FORCEPROP 1 LAST TOLERANCE 20%
J 0
(-9925 5800);
DISPLAY 0.489362 (-9925 5800);
PAINT SKYBLUE (-9925 5800);
FORCEPROP 1 LAST VALUE 22UF
J 0
(-9925 5900);
DISPLAY 0.489362 (-9925 5900);
PAINT SKYBLUE (-9925 5900);
FORCEPROP 1 LAST PART_NUMBER CH622KMEB02
J 0
(-9925 5700);
DISPLAY 0.489362 (-9925 5700);
PAINT SKYBLUE (-9925 5700);
FORCEPROP 1 LAST VOLTAGE 4V
J 0
(-9925 5850);
DISPLAY 0.489362 (-9925 5850);
PAINT SKYBLUE (-9925 5850);
FORCEPROP 1 LAST PACK_TYPE C0402
J 0
(-9925 5650);
DISPLAY 0.489362 (-9925 5650);
PAINT SKYBLUE (-9925 5650);
FORCEPROP 2 LAST CDS_LIB pure_quanta
J 0
(-9975 5850);
PAINT MONO (-9975 5850);
DISPLAY INVISIBLE (-9975 5850);
FORCEPROP 1 LAST PATH I103
J 0
(-9925 6000);
DISPLAY 0.978723 (-9925 6000);
PAINT WHITE (-9925 6000);
DISPLAY INVISIBLE (-9925 6000);
FORCEADD Q_CAP..1
(-9525 5850);
FORCEPROP 1 LAST LOCATION C2159
J 0
(-9475 5950);
DISPLAY 0.489362 (-9475 5950);
PAINT SKYBLUE (-9475 5950);
FORCEPROP 2 LAST $SEC 1
J 0
(-9475 6050);
DISPLAY 0.680851 (-9475 6050);
PAINT MONO (-9475 6050);
DISPLAY INVISIBLE (-9475 6050);
FORCEPROP 2 LAST CDS_SEC 1
J 0
(-9475 6050);
DISPLAY 1.021277 (-9475 6050);
DISPLAY INVISIBLE (-9475 6050);
FORCEPROP 1 LASTPIN (-9525 5950) $PN 1
J 0
(-9515 5930);
DISPLAY 0.489362 (-9515 5930);
FORCEPROP 1 LASTPIN (-9525 5750) $PN 2
J 0
(-9515 5730);
DISPLAY 0.489362 (-9515 5730);
FORCEPROP 1 LAST MATERIAL X6S
J 0
(-9475 5750);
DISPLAY 0.489362 (-9475 5750);
PAINT SKYBLUE (-9475 5750);
FORCEPROP 1 LAST TOLERANCE 20%
J 0
(-9475 5800);
DISPLAY 0.489362 (-9475 5800);
PAINT SKYBLUE (-9475 5800);
FORCEPROP 1 LAST VALUE 22UF
J 0
(-9475 5900);
DISPLAY 0.489362 (-9475 5900);
PAINT SKYBLUE (-9475 5900);
FORCEPROP 1 LAST PART_NUMBER CH622KMEB02
J 0
(-9475 5700);
DISPLAY 0.489362 (-9475 5700);
PAINT SKYBLUE (-9475 5700);
FORCEPROP 1 LAST VOLTAGE 4V
J 0
(-9475 5850);
DISPLAY 0.489362 (-9475 5850);
PAINT SKYBLUE (-9475 5850);
FORCEPROP 1 LAST PACK_TYPE C0402
J 0
(-9475 5650);
DISPLAY 0.489362 (-9475 5650);
PAINT SKYBLUE (-9475 5650);
FORCEPROP 2 LAST CDS_LIB pure_quanta
J 0
(-9525 5850);
PAINT MONO (-9525 5850);
DISPLAY INVISIBLE (-9525 5850);
FORCEPROP 1 LAST PATH I104
J 0
(-9475 6000);
DISPLAY 0.978723 (-9475 6000);
PAINT WHITE (-9475 6000);
DISPLAY INVISIBLE (-9475 6000);
FORCEADD UNIVERSAL_GND..1
(-9125 4675);
FORCEPROP 3 LASTPIN (-9125 4725) SIG_NAME GND\g
J 0
(-9115 4735);
DISPLAY 0.659574 (-9115 4735);
PAINT MONO (-9115 4735);
DISPLAY INVISIBLE (-9115 4735);
FORCEPROP 2 LAST CDS_LIB pure_quanta_power
J 0
(-9125 4675);
PAINT MONO (-9125 4675);
DISPLAY INVISIBLE (-9125 4675);
FORCEPROP 1 LAST PATH I105
J 0
(-9050 4675);
DISPLAY 0.872340 (-9050 4675);
PAINT AQUA (-9050 4675);
DISPLAY INVISIBLE (-9050 4675);
FORCEPROP 1 LAST HDL_POWER GND
J 1
(-9100 4600);
DISPLAY 0.872340 (-9100 4600);
PAINT GREEN (-9100 4600);
DISPLAY INVISIBLE (-9100 4600);
FORCEADD Q_CAP..1
(-9125 5050);
FORCEPROP 1 LAST LOCATION C3896
J 0
(-9075 5150);
DISPLAY 0.489362 (-9075 5150);
PAINT SKYBLUE (-9075 5150);
FORCEPROP 2 LAST $SEC 1
J 0
(-9075 5250);
DISPLAY 0.680851 (-9075 5250);
PAINT MONO (-9075 5250);
DISPLAY INVISIBLE (-9075 5250);
FORCEPROP 2 LAST CDS_SEC 1
J 0
(-9075 5250);
DISPLAY 1.021277 (-9075 5250);
DISPLAY INVISIBLE (-9075 5250);
FORCEPROP 1 LASTPIN (-9125 5150) $PN 1
J 0
(-9115 5130);
DISPLAY 0.489362 (-9115 5130);
FORCEPROP 1 LASTPIN (-9125 4950) $PN 2
J 0
(-9115 4930);
DISPLAY 0.489362 (-9115 4930);
FORCEPROP 1 LAST MATERIAL X6S
J 0
(-9075 4950);
DISPLAY 0.489362 (-9075 4950);
PAINT SKYBLUE (-9075 4950);
FORCEPROP 1 LAST TOLERANCE 20%
J 0
(-9075 5000);
DISPLAY 0.489362 (-9075 5000);
PAINT SKYBLUE (-9075 5000);
FORCEPROP 1 LAST VALUE 22UF
J 0
(-9075 5100);
DISPLAY 0.489362 (-9075 5100);
PAINT SKYBLUE (-9075 5100);
FORCEPROP 1 LAST PART_NUMBER CH622KMEB02
J 0
(-9075 4900);
DISPLAY 0.489362 (-9075 4900);
PAINT SKYBLUE (-9075 4900);
FORCEPROP 1 LAST VOLTAGE 4V
J 0
(-9075 5050);
DISPLAY 0.489362 (-9075 5050);
PAINT SKYBLUE (-9075 5050);
FORCEPROP 1 LAST PACK_TYPE C0402
J 0
(-9075 4850);
DISPLAY 0.489362 (-9075 4850);
PAINT SKYBLUE (-9075 4850);
FORCEPROP 2 LAST CDS_LIB pure_quanta
J 0
(-9125 5050);
PAINT MONO (-9125 5050);
DISPLAY INVISIBLE (-9125 5050);
FORCEPROP 1 LAST PATH I106
J 0
(-9075 5200);
DISPLAY 0.978723 (-9075 5200);
PAINT WHITE (-9075 5200);
DISPLAY INVISIBLE (-9075 5200);
FORCEADD UNIVERSAL_GND..1
(-9125 5475);
FORCEPROP 3 LASTPIN (-9125 5525) SIG_NAME GND\g
J 0
(-9115 5535);
DISPLAY 0.659574 (-9115 5535);
PAINT MONO (-9115 5535);
DISPLAY INVISIBLE (-9115 5535);
FORCEPROP 2 LAST CDS_LIB pure_quanta_power
J 0
(-9125 5475);
PAINT MONO (-9125 5475);
DISPLAY INVISIBLE (-9125 5475);
FORCEPROP 1 LAST PATH I107
J 0
(-9050 5475);
DISPLAY 0.872340 (-9050 5475);
PAINT AQUA (-9050 5475);
DISPLAY INVISIBLE (-9050 5475);
FORCEPROP 1 LAST HDL_POWER GND
J 1
(-9100 5400);
DISPLAY 0.872340 (-9100 5400);
PAINT GREEN (-9100 5400);
DISPLAY INVISIBLE (-9100 5400);
FORCEADD Q_CAP..1
(-9125 5850);
FORCEPROP 1 LAST LOCATION C2161
J 0
(-9075 5950);
DISPLAY 0.489362 (-9075 5950);
PAINT SKYBLUE (-9075 5950);
FORCEPROP 2 LAST $SEC 1
J 0
(-9075 6050);
DISPLAY 0.680851 (-9075 6050);
PAINT MONO (-9075 6050);
DISPLAY INVISIBLE (-9075 6050);
FORCEPROP 2 LAST CDS_SEC 1
J 0
(-9075 6050);
DISPLAY 1.021277 (-9075 6050);
DISPLAY INVISIBLE (-9075 6050);
FORCEPROP 1 LASTPIN (-9125 5950) $PN 1
J 0
(-9115 5930);
DISPLAY 0.489362 (-9115 5930);
FORCEPROP 1 LASTPIN (-9125 5750) $PN 2
J 0
(-9115 5730);
DISPLAY 0.489362 (-9115 5730);
FORCEPROP 1 LAST MATERIAL X6S
J 0
(-9075 5750);
DISPLAY 0.489362 (-9075 5750);
PAINT SKYBLUE (-9075 5750);
FORCEPROP 1 LAST TOLERANCE 20%
J 0
(-9075 5800);
DISPLAY 0.489362 (-9075 5800);
PAINT SKYBLUE (-9075 5800);
FORCEPROP 1 LAST VALUE 22UF
J 0
(-9075 5900);
DISPLAY 0.489362 (-9075 5900);
PAINT SKYBLUE (-9075 5900);
FORCEPROP 1 LAST PART_NUMBER CH622KMEB02
J 0
(-9075 5700);
DISPLAY 0.489362 (-9075 5700);
PAINT SKYBLUE (-9075 5700);
FORCEPROP 1 LAST VOLTAGE 4V
J 0
(-9075 5850);
DISPLAY 0.489362 (-9075 5850);
PAINT SKYBLUE (-9075 5850);
FORCEPROP 1 LAST PACK_TYPE C0402
J 0
(-9075 5650);
DISPLAY 0.489362 (-9075 5650);
PAINT SKYBLUE (-9075 5650);
FORCEPROP 2 LAST CDS_LIB pure_quanta
J 0
(-9125 5850);
PAINT MONO (-9125 5850);
DISPLAY INVISIBLE (-9125 5850);
FORCEPROP 1 LAST PATH I108
J 0
(-9075 6000);
DISPLAY 0.978723 (-9075 6000);
PAINT WHITE (-9075 6000);
DISPLAY INVISIBLE (-9075 6000);
FORCEADD Q_CAP..1
(-11325 5850);
FORCEPROP 1 LAST LOCATION C2147
J 0
(-11275 5950);
DISPLAY 0.489362 (-11275 5950);
PAINT SKYBLUE (-11275 5950);
FORCEPROP 2 LAST $SEC 1
J 0
(-11275 6050);
DISPLAY 0.680851 (-11275 6050);
PAINT MONO (-11275 6050);
DISPLAY INVISIBLE (-11275 6050);
FORCEPROP 2 LAST CDS_SEC 1
J 0
(-11275 6050);
DISPLAY 1.021277 (-11275 6050);
DISPLAY INVISIBLE (-11275 6050);
FORCEPROP 1 LASTPIN (-11325 5950) $PN 1
J 0
(-11315 5930);
DISPLAY 0.489362 (-11315 5930);
FORCEPROP 1 LASTPIN (-11325 5750) $PN 2
J 0
(-11315 5730);
DISPLAY 0.489362 (-11315 5730);
FORCEPROP 1 LAST MATERIAL X6S
J 0
(-11275 5750);
DISPLAY 0.489362 (-11275 5750);
PAINT SKYBLUE (-11275 5750);
FORCEPROP 1 LAST TOLERANCE 20%
J 0
(-11275 5800);
DISPLAY 0.489362 (-11275 5800);
PAINT SKYBLUE (-11275 5800);
FORCEPROP 1 LAST VALUE 22UF
J 0
(-11275 5900);
DISPLAY 0.489362 (-11275 5900);
PAINT SKYBLUE (-11275 5900);
FORCEPROP 1 LAST PART_NUMBER CH622KMEB02
J 0
(-11275 5700);
DISPLAY 0.489362 (-11275 5700);
PAINT SKYBLUE (-11275 5700);
FORCEPROP 1 LAST VOLTAGE 4V
J 0
(-11275 5850);
DISPLAY 0.489362 (-11275 5850);
PAINT SKYBLUE (-11275 5850);
FORCEPROP 1 LAST PACK_TYPE C0402
J 0
(-11275 5650);
DISPLAY 0.489362 (-11275 5650);
PAINT SKYBLUE (-11275 5650);
FORCEPROP 2 LAST CDS_LIB pure_quanta
J 0
(-11325 5850);
PAINT MONO (-11325 5850);
DISPLAY INVISIBLE (-11325 5850);
FORCEPROP 1 LAST PATH I109
J 0
(-11275 6000);
DISPLAY 0.978723 (-11275 6000);
PAINT WHITE (-11275 6000);
DISPLAY INVISIBLE (-11275 6000);
FORCEADD Q_CAP..1
(-13125 1600);
FORCEPROP 1 LAST LOCATION C2133
J 0
(-13075 1700);
DISPLAY 0.489362 (-13075 1700);
PAINT SKYBLUE (-13075 1700);
FORCEPROP 2 LAST $SEC 1
J 0
(-13075 1800);
DISPLAY 0.680851 (-13075 1800);
PAINT MONO (-13075 1800);
DISPLAY INVISIBLE (-13075 1800);
FORCEPROP 2 LAST CDS_SEC 1
J 0
(-13075 1800);
DISPLAY 1.021277 (-13075 1800);
DISPLAY INVISIBLE (-13075 1800);
FORCEPROP 1 LASTPIN (-13125 1700) $PN 1
J 0
(-13115 1680);
DISPLAY 0.489362 (-13115 1680);
FORCEPROP 1 LASTPIN (-13125 1500) $PN 2
J 0
(-13115 1480);
DISPLAY 0.489362 (-13115 1480);
FORCEPROP 1 LAST MATERIAL X6S
J 0
(-13075 1500);
DISPLAY 0.489362 (-13075 1500);
PAINT SKYBLUE (-13075 1500);
FORCEPROP 1 LAST TOLERANCE 20%
J 0
(-13075 1550);
DISPLAY 0.489362 (-13075 1550);
PAINT SKYBLUE (-13075 1550);
FORCEPROP 1 LAST VALUE 22UF
J 0
(-13075 1650);
DISPLAY 0.489362 (-13075 1650);
PAINT SKYBLUE (-13075 1650);
FORCEPROP 1 LAST PART_NUMBER CH622KMEB02
J 0
(-13075 1450);
DISPLAY 0.489362 (-13075 1450);
PAINT SKYBLUE (-13075 1450);
FORCEPROP 1 LAST VOLTAGE 4V
J 0
(-13075 1600);
DISPLAY 0.489362 (-13075 1600);
PAINT SKYBLUE (-13075 1600);
FORCEPROP 1 LAST PACK_TYPE C0402
J 0
(-13075 1400);
DISPLAY 0.489362 (-13075 1400);
PAINT SKYBLUE (-13075 1400);
FORCEPROP 2 LAST CDS_LIB pure_quanta
J 0
(-13125 1600);
PAINT MONO (-13125 1600);
DISPLAY INVISIBLE (-13125 1600);
FORCEPROP 1 LAST PATH I110
J 0
(-13075 1750);
DISPLAY 0.978723 (-13075 1750);
PAINT WHITE (-13075 1750);
DISPLAY INVISIBLE (-13075 1750);
FORCEADD UNIVERSAL_POWER..1
(-13125 1875);
FORCEPROP 3 LASTPIN (-13125 1825) SIG_NAME PVDD11_S3_P0\g
J 0
(-13115 1835);
DISPLAY 0.659574 (-13115 1835);
PAINT MONO (-13115 1835);
DISPLAY INVISIBLE (-13115 1835);
FORCEPROP 1 LAST HDL_POWER PVDD11_S3_P0
J 1
(-13125 1925);
DISPLAY 0.489362 (-13125 1925);
PAINT GREEN (-13125 1925);
FORCEPROP 2 LAST CDS_LIB pure_quanta_power
J 0
(-13125 1875);
DISPLAY INVISIBLE (-13125 1875);
FORCEPROP 1 LAST PATH I111
J 0
(-13075 1900);
DISPLAY 0.872340 (-13075 1900);
PAINT AQUA (-13075 1900);
DISPLAY INVISIBLE (-13075 1900);
FORCEADD Q_CAP..1
(-12675 1600);
FORCEPROP 1 LAST LOCATION C2138
J 0
(-12625 1700);
DISPLAY 0.489362 (-12625 1700);
PAINT SKYBLUE (-12625 1700);
FORCEPROP 2 LAST $SEC 1
J 0
(-12625 1800);
DISPLAY 0.680851 (-12625 1800);
PAINT MONO (-12625 1800);
DISPLAY INVISIBLE (-12625 1800);
FORCEPROP 2 LAST CDS_SEC 1
J 0
(-12625 1800);
DISPLAY 1.021277 (-12625 1800);
DISPLAY INVISIBLE (-12625 1800);
FORCEPROP 1 LASTPIN (-12675 1700) $PN 1
J 0
(-12665 1680);
DISPLAY 0.489362 (-12665 1680);
FORCEPROP 1 LASTPIN (-12675 1500) $PN 2
J 0
(-12665 1480);
DISPLAY 0.489362 (-12665 1480);
FORCEPROP 1 LAST MATERIAL X6S
J 0
(-12625 1500);
DISPLAY 0.489362 (-12625 1500);
PAINT SKYBLUE (-12625 1500);
FORCEPROP 1 LAST TOLERANCE 20%
J 0
(-12625 1550);
DISPLAY 0.489362 (-12625 1550);
PAINT SKYBLUE (-12625 1550);
FORCEPROP 1 LAST VALUE 22UF
J 0
(-12625 1650);
DISPLAY 0.489362 (-12625 1650);
PAINT SKYBLUE (-12625 1650);
FORCEPROP 1 LAST PART_NUMBER CH622KMEB02
J 0
(-12625 1450);
DISPLAY 0.489362 (-12625 1450);
PAINT SKYBLUE (-12625 1450);
FORCEPROP 1 LAST VOLTAGE 4V
J 0
(-12625 1600);
DISPLAY 0.489362 (-12625 1600);
PAINT SKYBLUE (-12625 1600);
FORCEPROP 1 LAST PACK_TYPE C0402
J 0
(-12625 1400);
DISPLAY 0.489362 (-12625 1400);
PAINT SKYBLUE (-12625 1400);
FORCEPROP 2 LAST CDS_LIB pure_quanta
J 0
(-12675 1600);
PAINT MONO (-12675 1600);
DISPLAY INVISIBLE (-12675 1600);
FORCEPROP 1 LAST PATH I112
J 0
(-12625 1750);
DISPLAY 0.978723 (-12625 1750);
PAINT WHITE (-12625 1750);
DISPLAY INVISIBLE (-12625 1750);
FORCEADD Q_CAP..1
(-13125 2350);
FORCEPROP 1 LAST LOCATION C2132
J 0
(-13075 2450);
DISPLAY 0.489362 (-13075 2450);
PAINT SKYBLUE (-13075 2450);
FORCEPROP 2 LAST $SEC 1
J 0
(-13075 2550);
DISPLAY 0.680851 (-13075 2550);
PAINT MONO (-13075 2550);
DISPLAY INVISIBLE (-13075 2550);
FORCEPROP 2 LAST CDS_SEC 1
J 0
(-13075 2550);
DISPLAY 1.021277 (-13075 2550);
DISPLAY INVISIBLE (-13075 2550);
FORCEPROP 1 LASTPIN (-13125 2450) $PN 1
J 0
(-13115 2430);
DISPLAY 0.489362 (-13115 2430);
FORCEPROP 1 LASTPIN (-13125 2250) $PN 2
J 0
(-13115 2230);
DISPLAY 0.489362 (-13115 2230);
FORCEPROP 1 LAST MATERIAL X6S
J 0
(-13075 2250);
DISPLAY 0.489362 (-13075 2250);
PAINT SKYBLUE (-13075 2250);
FORCEPROP 1 LAST TOLERANCE 20%
J 0
(-13075 2300);
DISPLAY 0.489362 (-13075 2300);
PAINT SKYBLUE (-13075 2300);
FORCEPROP 1 LAST VALUE 22UF
J 0
(-13075 2400);
DISPLAY 0.489362 (-13075 2400);
PAINT SKYBLUE (-13075 2400);
FORCEPROP 1 LAST PART_NUMBER CH622KMEB02
J 0
(-13075 2200);
DISPLAY 0.489362 (-13075 2200);
PAINT SKYBLUE (-13075 2200);
FORCEPROP 1 LAST VOLTAGE 4V
J 0
(-13075 2350);
DISPLAY 0.489362 (-13075 2350);
PAINT SKYBLUE (-13075 2350);
FORCEPROP 1 LAST PACK_TYPE C0402
J 0
(-13075 2150);
DISPLAY 0.489362 (-13075 2150);
PAINT SKYBLUE (-13075 2150);
FORCEPROP 2 LAST CDS_LIB pure_quanta
J 0
(-13125 2350);
PAINT MONO (-13125 2350);
DISPLAY INVISIBLE (-13125 2350);
FORCEPROP 1 LAST PATH I113
J 0
(-13075 2500);
DISPLAY 0.978723 (-13075 2500);
PAINT WHITE (-13075 2500);
DISPLAY INVISIBLE (-13075 2500);
FORCEADD UNIVERSAL_POWER..1
(-13125 2625);
FORCEPROP 3 LASTPIN (-13125 2575) SIG_NAME PVDD11_S3_P0\g
J 0
(-13115 2585);
DISPLAY 0.659574 (-13115 2585);
PAINT MONO (-13115 2585);
DISPLAY INVISIBLE (-13115 2585);
FORCEPROP 1 LAST HDL_POWER PVDD11_S3_P0
J 1
(-13125 2675);
DISPLAY 0.489362 (-13125 2675);
PAINT GREEN (-13125 2675);
FORCEPROP 2 LAST CDS_LIB pure_quanta_power
J 0
(-13125 2625);
DISPLAY INVISIBLE (-13125 2625);
FORCEPROP 1 LAST PATH I114
J 0
(-13075 2650);
DISPLAY 0.872340 (-13075 2650);
PAINT AQUA (-13075 2650);
DISPLAY INVISIBLE (-13075 2650);
FORCEADD Q_CAP..1
(-12675 2350);
FORCEPROP 1 LAST LOCATION C2137
J 0
(-12625 2450);
DISPLAY 0.489362 (-12625 2450);
PAINT SKYBLUE (-12625 2450);
FORCEPROP 2 LAST $SEC 1
J 0
(-12625 2550);
DISPLAY 0.680851 (-12625 2550);
PAINT MONO (-12625 2550);
DISPLAY INVISIBLE (-12625 2550);
FORCEPROP 2 LAST CDS_SEC 1
J 0
(-12625 2550);
DISPLAY 1.021277 (-12625 2550);
DISPLAY INVISIBLE (-12625 2550);
FORCEPROP 1 LASTPIN (-12675 2450) $PN 1
J 0
(-12665 2430);
DISPLAY 0.489362 (-12665 2430);
FORCEPROP 1 LASTPIN (-12675 2250) $PN 2
J 0
(-12665 2230);
DISPLAY 0.489362 (-12665 2230);
FORCEPROP 1 LAST MATERIAL X6S
J 0
(-12625 2250);
DISPLAY 0.489362 (-12625 2250);
PAINT SKYBLUE (-12625 2250);
FORCEPROP 1 LAST TOLERANCE 20%
J 0
(-12625 2300);
DISPLAY 0.489362 (-12625 2300);
PAINT SKYBLUE (-12625 2300);
FORCEPROP 1 LAST VALUE 22UF
J 0
(-12625 2400);
DISPLAY 0.489362 (-12625 2400);
PAINT SKYBLUE (-12625 2400);
FORCEPROP 1 LAST PART_NUMBER CH622KMEB02
J 0
(-12625 2200);
DISPLAY 0.489362 (-12625 2200);
PAINT SKYBLUE (-12625 2200);
FORCEPROP 1 LAST VOLTAGE 4V
J 0
(-12625 2350);
DISPLAY 0.489362 (-12625 2350);
PAINT SKYBLUE (-12625 2350);
FORCEPROP 1 LAST PACK_TYPE C0402
J 0
(-12625 2150);
DISPLAY 0.489362 (-12625 2150);
PAINT SKYBLUE (-12625 2150);
FORCEPROP 2 LAST CDS_LIB pure_quanta
J 0
(-12675 2350);
PAINT MONO (-12675 2350);
DISPLAY INVISIBLE (-12675 2350);
FORCEPROP 1 LAST PATH I115
J 0
(-12625 2500);
DISPLAY 0.978723 (-12625 2500);
PAINT WHITE (-12625 2500);
DISPLAY INVISIBLE (-12625 2500);
FORCEADD Q_CAP..1
(-12225 1600);
FORCEPROP 1 LAST LOCATION C3890
J 0
(-12175 1700);
DISPLAY 0.489362 (-12175 1700);
PAINT SKYBLUE (-12175 1700);
FORCEPROP 2 LAST $SEC 1
J 0
(-12175 1800);
DISPLAY 0.680851 (-12175 1800);
PAINT MONO (-12175 1800);
DISPLAY INVISIBLE (-12175 1800);
FORCEPROP 2 LAST CDS_SEC 1
J 0
(-12175 1800);
DISPLAY 1.021277 (-12175 1800);
DISPLAY INVISIBLE (-12175 1800);
FORCEPROP 1 LASTPIN (-12225 1700) $PN 1
J 0
(-12215 1680);
DISPLAY 0.489362 (-12215 1680);
FORCEPROP 1 LASTPIN (-12225 1500) $PN 2
J 0
(-12215 1480);
DISPLAY 0.489362 (-12215 1480);
FORCEPROP 1 LAST MATERIAL X6S
J 0
(-12175 1500);
DISPLAY 0.489362 (-12175 1500);
PAINT SKYBLUE (-12175 1500);
FORCEPROP 1 LAST TOLERANCE 20%
J 0
(-12175 1550);
DISPLAY 0.489362 (-12175 1550);
PAINT SKYBLUE (-12175 1550);
FORCEPROP 1 LAST VALUE 22UF
J 0
(-12175 1650);
DISPLAY 0.489362 (-12175 1650);
PAINT SKYBLUE (-12175 1650);
FORCEPROP 1 LAST PART_NUMBER CH622KMEB02
J 0
(-12175 1450);
DISPLAY 0.489362 (-12175 1450);
PAINT SKYBLUE (-12175 1450);
FORCEPROP 1 LAST VOLTAGE 4V
J 0
(-12175 1600);
DISPLAY 0.489362 (-12175 1600);
PAINT SKYBLUE (-12175 1600);
FORCEPROP 1 LAST PACK_TYPE C0402
J 0
(-12175 1400);
DISPLAY 0.489362 (-12175 1400);
PAINT SKYBLUE (-12175 1400);
FORCEPROP 2 LAST CDS_LIB pure_quanta
J 0
(-12225 1600);
PAINT MONO (-12225 1600);
DISPLAY INVISIBLE (-12225 1600);
FORCEPROP 1 LAST PATH I116
J 0
(-12175 1750);
DISPLAY 0.978723 (-12175 1750);
PAINT WHITE (-12175 1750);
DISPLAY INVISIBLE (-12175 1750);
FORCEADD Q_CAP..1
(-11775 1600);
FORCEPROP 1 LAST LOCATION C3891
J 0
(-11725 1700);
DISPLAY 0.489362 (-11725 1700);
PAINT SKYBLUE (-11725 1700);
FORCEPROP 2 LAST $SEC 1
J 0
(-11725 1800);
DISPLAY 0.680851 (-11725 1800);
PAINT MONO (-11725 1800);
DISPLAY INVISIBLE (-11725 1800);
FORCEPROP 2 LAST CDS_SEC 1
J 0
(-11725 1800);
DISPLAY 1.021277 (-11725 1800);
DISPLAY INVISIBLE (-11725 1800);
FORCEPROP 1 LASTPIN (-11775 1700) $PN 1
J 0
(-11765 1680);
DISPLAY 0.489362 (-11765 1680);
FORCEPROP 1 LASTPIN (-11775 1500) $PN 2
J 0
(-11765 1480);
DISPLAY 0.489362 (-11765 1480);
FORCEPROP 1 LAST MATERIAL X6S
J 0
(-11725 1500);
DISPLAY 0.489362 (-11725 1500);
PAINT SKYBLUE (-11725 1500);
FORCEPROP 1 LAST TOLERANCE 20%
J 0
(-11725 1550);
DISPLAY 0.489362 (-11725 1550);
PAINT SKYBLUE (-11725 1550);
FORCEPROP 1 LAST VALUE 22UF
J 0
(-11725 1650);
DISPLAY 0.489362 (-11725 1650);
PAINT SKYBLUE (-11725 1650);
FORCEPROP 1 LAST PART_NUMBER CH622KMEB02
J 0
(-11725 1450);
DISPLAY 0.489362 (-11725 1450);
PAINT SKYBLUE (-11725 1450);
FORCEPROP 1 LAST VOLTAGE 4V
J 0
(-11725 1600);
DISPLAY 0.489362 (-11725 1600);
PAINT SKYBLUE (-11725 1600);
FORCEPROP 1 LAST PACK_TYPE C0402
J 0
(-11725 1400);
DISPLAY 0.489362 (-11725 1400);
PAINT SKYBLUE (-11725 1400);
FORCEPROP 2 LAST CDS_LIB pure_quanta
J 0
(-11775 1600);
PAINT MONO (-11775 1600);
DISPLAY INVISIBLE (-11775 1600);
FORCEPROP 1 LAST PATH I117
J 0
(-11725 1750);
DISPLAY 0.978723 (-11725 1750);
PAINT WHITE (-11725 1750);
DISPLAY INVISIBLE (-11725 1750);
FORCEADD Q_CAP..1
(-11325 1600);
FORCEPROP 1 LAST LOCATION C3892
J 0
(-11275 1700);
DISPLAY 0.489362 (-11275 1700);
PAINT SKYBLUE (-11275 1700);
FORCEPROP 2 LAST $SEC 1
J 0
(-11275 1800);
DISPLAY 0.680851 (-11275 1800);
PAINT MONO (-11275 1800);
DISPLAY INVISIBLE (-11275 1800);
FORCEPROP 2 LAST CDS_SEC 1
J 0
(-11275 1800);
DISPLAY 1.021277 (-11275 1800);
DISPLAY INVISIBLE (-11275 1800);
FORCEPROP 1 LASTPIN (-11325 1700) $PN 1
J 0
(-11315 1680);
DISPLAY 0.489362 (-11315 1680);
FORCEPROP 1 LASTPIN (-11325 1500) $PN 2
J 0
(-11315 1480);
DISPLAY 0.489362 (-11315 1480);
FORCEPROP 1 LAST MATERIAL X6S
J 0
(-11275 1500);
DISPLAY 0.489362 (-11275 1500);
PAINT SKYBLUE (-11275 1500);
FORCEPROP 1 LAST TOLERANCE 20%
J 0
(-11275 1550);
DISPLAY 0.489362 (-11275 1550);
PAINT SKYBLUE (-11275 1550);
FORCEPROP 1 LAST VALUE 22UF
J 0
(-11275 1650);
DISPLAY 0.489362 (-11275 1650);
PAINT SKYBLUE (-11275 1650);
FORCEPROP 1 LAST PART_NUMBER CH622KMEB02
J 0
(-11275 1450);
DISPLAY 0.489362 (-11275 1450);
PAINT SKYBLUE (-11275 1450);
FORCEPROP 1 LAST VOLTAGE 4V
J 0
(-11275 1600);
DISPLAY 0.489362 (-11275 1600);
PAINT SKYBLUE (-11275 1600);
FORCEPROP 1 LAST PACK_TYPE C0402
J 0
(-11275 1400);
DISPLAY 0.489362 (-11275 1400);
PAINT SKYBLUE (-11275 1400);
FORCEPROP 2 LAST CDS_LIB pure_quanta
J 0
(-11325 1600);
PAINT MONO (-11325 1600);
DISPLAY INVISIBLE (-11325 1600);
FORCEPROP 1 LAST PATH I118
J 0
(-11275 1750);
DISPLAY 0.978723 (-11275 1750);
PAINT WHITE (-11275 1750);
DISPLAY INVISIBLE (-11275 1750);
FORCEADD UNIVERSAL_GND..1
(-10875 1225);
FORCEPROP 3 LASTPIN (-10875 1275) SIG_NAME GND\g
J 0
(-10865 1285);
DISPLAY 0.659574 (-10865 1285);
PAINT MONO (-10865 1285);
DISPLAY INVISIBLE (-10865 1285);
FORCEPROP 2 LAST CDS_LIB pure_quanta_power
J 0
(-10875 1225);
PAINT MONO (-10875 1225);
DISPLAY INVISIBLE (-10875 1225);
FORCEPROP 1 LAST PATH I119
J 0
(-10800 1225);
DISPLAY 0.872340 (-10800 1225);
PAINT AQUA (-10800 1225);
DISPLAY INVISIBLE (-10800 1225);
FORCEPROP 1 LAST HDL_POWER GND
J 1
(-10850 1150);
DISPLAY 0.872340 (-10850 1150);
PAINT GREEN (-10850 1150);
DISPLAY INVISIBLE (-10850 1150);
FORCEADD Q_CAP..1
(-10875 1600);
FORCEPROP 1 LAST LOCATION C3893
J 0
(-10825 1700);
DISPLAY 0.489362 (-10825 1700);
PAINT SKYBLUE (-10825 1700);
FORCEPROP 2 LAST $SEC 1
J 0
(-10825 1800);
DISPLAY 0.680851 (-10825 1800);
PAINT MONO (-10825 1800);
DISPLAY INVISIBLE (-10825 1800);
FORCEPROP 2 LAST CDS_SEC 1
J 0
(-10825 1800);
DISPLAY 1.021277 (-10825 1800);
DISPLAY INVISIBLE (-10825 1800);
FORCEPROP 1 LASTPIN (-10875 1700) $PN 1
J 0
(-10865 1680);
DISPLAY 0.489362 (-10865 1680);
FORCEPROP 1 LASTPIN (-10875 1500) $PN 2
J 0
(-10865 1480);
DISPLAY 0.489362 (-10865 1480);
FORCEPROP 1 LAST MATERIAL X6S
J 0
(-10825 1500);
DISPLAY 0.489362 (-10825 1500);
PAINT SKYBLUE (-10825 1500);
FORCEPROP 1 LAST TOLERANCE 20%
J 0
(-10825 1550);
DISPLAY 0.489362 (-10825 1550);
PAINT SKYBLUE (-10825 1550);
FORCEPROP 1 LAST VALUE 22UF
J 0
(-10825 1650);
DISPLAY 0.489362 (-10825 1650);
PAINT SKYBLUE (-10825 1650);
FORCEPROP 1 LAST PART_NUMBER CH622KMEB02
J 0
(-10825 1450);
DISPLAY 0.489362 (-10825 1450);
PAINT SKYBLUE (-10825 1450);
FORCEPROP 1 LAST VOLTAGE 4V
J 0
(-10825 1600);
DISPLAY 0.489362 (-10825 1600);
PAINT SKYBLUE (-10825 1600);
FORCEPROP 1 LAST PACK_TYPE C0402
J 0
(-10825 1400);
DISPLAY 0.489362 (-10825 1400);
PAINT SKYBLUE (-10825 1400);
FORCEPROP 2 LAST CDS_LIB pure_quanta
J 0
(-10875 1600);
PAINT MONO (-10875 1600);
DISPLAY INVISIBLE (-10875 1600);
FORCEPROP 1 LAST PATH I120
J 0
(-10825 1750);
DISPLAY 0.978723 (-10825 1750);
PAINT WHITE (-10825 1750);
DISPLAY INVISIBLE (-10825 1750);
FORCEADD Q_CAP..1
(-12225 2350);
FORCEPROP 1 LAST LOCATION C2142
J 0
(-12175 2450);
DISPLAY 0.489362 (-12175 2450);
PAINT SKYBLUE (-12175 2450);
FORCEPROP 2 LAST $SEC 1
J 0
(-12175 2550);
DISPLAY 0.680851 (-12175 2550);
PAINT MONO (-12175 2550);
DISPLAY INVISIBLE (-12175 2550);
FORCEPROP 2 LAST CDS_SEC 1
J 0
(-12175 2550);
DISPLAY 1.021277 (-12175 2550);
DISPLAY INVISIBLE (-12175 2550);
FORCEPROP 1 LASTPIN (-12225 2450) $PN 1
J 0
(-12215 2430);
DISPLAY 0.489362 (-12215 2430);
FORCEPROP 1 LASTPIN (-12225 2250) $PN 2
J 0
(-12215 2230);
DISPLAY 0.489362 (-12215 2230);
FORCEPROP 1 LAST MATERIAL X6S
J 0
(-12175 2250);
DISPLAY 0.489362 (-12175 2250);
PAINT SKYBLUE (-12175 2250);
FORCEPROP 1 LAST TOLERANCE 20%
J 0
(-12175 2300);
DISPLAY 0.489362 (-12175 2300);
PAINT SKYBLUE (-12175 2300);
FORCEPROP 1 LAST VALUE 22UF
J 0
(-12175 2400);
DISPLAY 0.489362 (-12175 2400);
PAINT SKYBLUE (-12175 2400);
FORCEPROP 1 LAST PART_NUMBER CH622KMEB02
J 0
(-12175 2200);
DISPLAY 0.489362 (-12175 2200);
PAINT SKYBLUE (-12175 2200);
FORCEPROP 1 LAST VOLTAGE 4V
J 0
(-12175 2350);
DISPLAY 0.489362 (-12175 2350);
PAINT SKYBLUE (-12175 2350);
FORCEPROP 1 LAST PACK_TYPE C0402
J 0
(-12175 2150);
DISPLAY 0.489362 (-12175 2150);
PAINT SKYBLUE (-12175 2150);
FORCEPROP 2 LAST CDS_LIB pure_quanta
J 0
(-12225 2350);
PAINT MONO (-12225 2350);
DISPLAY INVISIBLE (-12225 2350);
FORCEPROP 1 LAST PATH I121
J 0
(-12175 2500);
DISPLAY 0.978723 (-12175 2500);
PAINT WHITE (-12175 2500);
DISPLAY INVISIBLE (-12175 2500);
FORCEADD Q_CAP..1
(-11775 2350);
FORCEPROP 1 LAST LOCATION C2146
J 0
(-11725 2450);
DISPLAY 0.489362 (-11725 2450);
PAINT SKYBLUE (-11725 2450);
FORCEPROP 2 LAST $SEC 1
J 0
(-11725 2550);
DISPLAY 0.680851 (-11725 2550);
PAINT MONO (-11725 2550);
DISPLAY INVISIBLE (-11725 2550);
FORCEPROP 2 LAST CDS_SEC 1
J 0
(-11725 2550);
DISPLAY 1.021277 (-11725 2550);
DISPLAY INVISIBLE (-11725 2550);
FORCEPROP 1 LASTPIN (-11775 2450) $PN 1
J 0
(-11765 2430);
DISPLAY 0.489362 (-11765 2430);
FORCEPROP 1 LASTPIN (-11775 2250) $PN 2
J 0
(-11765 2230);
DISPLAY 0.489362 (-11765 2230);
FORCEPROP 1 LAST MATERIAL X6S
J 0
(-11725 2250);
DISPLAY 0.489362 (-11725 2250);
PAINT SKYBLUE (-11725 2250);
FORCEPROP 1 LAST TOLERANCE 20%
J 0
(-11725 2300);
DISPLAY 0.489362 (-11725 2300);
PAINT SKYBLUE (-11725 2300);
FORCEPROP 1 LAST VALUE 22UF
J 0
(-11725 2400);
DISPLAY 0.489362 (-11725 2400);
PAINT SKYBLUE (-11725 2400);
FORCEPROP 1 LAST PART_NUMBER CH622KMEB02
J 0
(-11725 2200);
DISPLAY 0.489362 (-11725 2200);
PAINT SKYBLUE (-11725 2200);
FORCEPROP 1 LAST VOLTAGE 4V
J 0
(-11725 2350);
DISPLAY 0.489362 (-11725 2350);
PAINT SKYBLUE (-11725 2350);
FORCEPROP 1 LAST PACK_TYPE C0402
J 0
(-11725 2150);
DISPLAY 0.489362 (-11725 2150);
PAINT SKYBLUE (-11725 2150);
FORCEPROP 2 LAST CDS_LIB pure_quanta
J 0
(-11775 2350);
PAINT MONO (-11775 2350);
DISPLAY INVISIBLE (-11775 2350);
FORCEPROP 1 LAST PATH I122
J 0
(-11725 2500);
DISPLAY 0.978723 (-11725 2500);
PAINT WHITE (-11725 2500);
DISPLAY INVISIBLE (-11725 2500);
FORCEADD Q_CAP..1
(-11325 2350);
FORCEPROP 1 LAST LOCATION C2150
J 0
(-11275 2450);
DISPLAY 0.489362 (-11275 2450);
PAINT SKYBLUE (-11275 2450);
FORCEPROP 2 LAST $SEC 1
J 0
(-11275 2550);
DISPLAY 0.680851 (-11275 2550);
PAINT MONO (-11275 2550);
DISPLAY INVISIBLE (-11275 2550);
FORCEPROP 2 LAST CDS_SEC 1
J 0
(-11275 2550);
DISPLAY 1.021277 (-11275 2550);
DISPLAY INVISIBLE (-11275 2550);
FORCEPROP 1 LASTPIN (-11325 2450) $PN 1
J 0
(-11315 2430);
DISPLAY 0.489362 (-11315 2430);
FORCEPROP 1 LASTPIN (-11325 2250) $PN 2
J 0
(-11315 2230);
DISPLAY 0.489362 (-11315 2230);
FORCEPROP 1 LAST MATERIAL X6S
J 0
(-11275 2250);
DISPLAY 0.489362 (-11275 2250);
PAINT SKYBLUE (-11275 2250);
FORCEPROP 1 LAST TOLERANCE 20%
J 0
(-11275 2300);
DISPLAY 0.489362 (-11275 2300);
PAINT SKYBLUE (-11275 2300);
FORCEPROP 1 LAST VALUE 22UF
J 0
(-11275 2400);
DISPLAY 0.489362 (-11275 2400);
PAINT SKYBLUE (-11275 2400);
FORCEPROP 1 LAST PART_NUMBER CH622KMEB02
J 0
(-11275 2200);
DISPLAY 0.489362 (-11275 2200);
PAINT SKYBLUE (-11275 2200);
FORCEPROP 1 LAST VOLTAGE 4V
J 0
(-11275 2350);
DISPLAY 0.489362 (-11275 2350);
PAINT SKYBLUE (-11275 2350);
FORCEPROP 1 LAST PACK_TYPE C0402
J 0
(-11275 2150);
DISPLAY 0.489362 (-11275 2150);
PAINT SKYBLUE (-11275 2150);
FORCEPROP 2 LAST CDS_LIB pure_quanta
J 0
(-11325 2350);
PAINT MONO (-11325 2350);
DISPLAY INVISIBLE (-11325 2350);
FORCEPROP 1 LAST PATH I123
J 0
(-11275 2500);
DISPLAY 0.978723 (-11275 2500);
PAINT WHITE (-11275 2500);
DISPLAY INVISIBLE (-11275 2500);
FORCEADD Q_CAP..1
(-10875 2350);
FORCEPROP 1 LAST LOCATION C2153
J 0
(-10825 2450);
DISPLAY 0.489362 (-10825 2450);
PAINT SKYBLUE (-10825 2450);
FORCEPROP 2 LAST $SEC 1
J 0
(-10825 2550);
DISPLAY 0.680851 (-10825 2550);
PAINT MONO (-10825 2550);
DISPLAY INVISIBLE (-10825 2550);
FORCEPROP 2 LAST CDS_SEC 1
J 0
(-10825 2550);
DISPLAY 1.021277 (-10825 2550);
DISPLAY INVISIBLE (-10825 2550);
FORCEPROP 1 LASTPIN (-10875 2450) $PN 1
J 0
(-10865 2430);
DISPLAY 0.489362 (-10865 2430);
FORCEPROP 1 LASTPIN (-10875 2250) $PN 2
J 0
(-10865 2230);
DISPLAY 0.489362 (-10865 2230);
FORCEPROP 1 LAST MATERIAL X6S
J 0
(-10825 2250);
DISPLAY 0.489362 (-10825 2250);
PAINT SKYBLUE (-10825 2250);
FORCEPROP 1 LAST TOLERANCE 20%
J 0
(-10825 2300);
DISPLAY 0.489362 (-10825 2300);
PAINT SKYBLUE (-10825 2300);
FORCEPROP 1 LAST VALUE 22UF
J 0
(-10825 2400);
DISPLAY 0.489362 (-10825 2400);
PAINT SKYBLUE (-10825 2400);
FORCEPROP 1 LAST PART_NUMBER CH622KMEB02
J 0
(-10825 2200);
DISPLAY 0.489362 (-10825 2200);
PAINT SKYBLUE (-10825 2200);
FORCEPROP 1 LAST VOLTAGE 4V
J 0
(-10825 2350);
DISPLAY 0.489362 (-10825 2350);
PAINT SKYBLUE (-10825 2350);
FORCEPROP 1 LAST PACK_TYPE C0402
J 0
(-10825 2150);
DISPLAY 0.489362 (-10825 2150);
PAINT SKYBLUE (-10825 2150);
FORCEPROP 2 LAST CDS_LIB pure_quanta
J 0
(-10875 2350);
PAINT MONO (-10875 2350);
DISPLAY INVISIBLE (-10875 2350);
FORCEPROP 1 LAST PATH I124
J 0
(-10825 2500);
DISPLAY 0.978723 (-10825 2500);
PAINT WHITE (-10825 2500);
DISPLAY INVISIBLE (-10825 2500);
FORCEADD Q_CAP..1
(-10425 2350);
FORCEPROP 1 LAST LOCATION C2156
J 0
(-10375 2450);
DISPLAY 0.489362 (-10375 2450);
PAINT SKYBLUE (-10375 2450);
FORCEPROP 2 LAST $SEC 1
J 0
(-10375 2550);
DISPLAY 0.680851 (-10375 2550);
PAINT MONO (-10375 2550);
DISPLAY INVISIBLE (-10375 2550);
FORCEPROP 2 LAST CDS_SEC 1
J 0
(-10375 2550);
DISPLAY 1.021277 (-10375 2550);
DISPLAY INVISIBLE (-10375 2550);
FORCEPROP 1 LASTPIN (-10425 2450) $PN 1
J 0
(-10415 2430);
DISPLAY 0.489362 (-10415 2430);
FORCEPROP 1 LASTPIN (-10425 2250) $PN 2
J 0
(-10415 2230);
DISPLAY 0.489362 (-10415 2230);
FORCEPROP 1 LAST MATERIAL X6S
J 0
(-10375 2250);
DISPLAY 0.489362 (-10375 2250);
PAINT SKYBLUE (-10375 2250);
FORCEPROP 1 LAST TOLERANCE 20%
J 0
(-10375 2300);
DISPLAY 0.489362 (-10375 2300);
PAINT SKYBLUE (-10375 2300);
FORCEPROP 1 LAST VALUE 22UF
J 0
(-10375 2400);
DISPLAY 0.489362 (-10375 2400);
PAINT SKYBLUE (-10375 2400);
FORCEPROP 1 LAST PART_NUMBER CH622KMEB02
J 0
(-10375 2200);
DISPLAY 0.489362 (-10375 2200);
PAINT SKYBLUE (-10375 2200);
FORCEPROP 1 LAST VOLTAGE 4V
J 0
(-10375 2350);
DISPLAY 0.489362 (-10375 2350);
PAINT SKYBLUE (-10375 2350);
FORCEPROP 1 LAST PACK_TYPE C0402
J 0
(-10375 2150);
DISPLAY 0.489362 (-10375 2150);
PAINT SKYBLUE (-10375 2150);
FORCEPROP 2 LAST CDS_LIB pure_quanta
J 0
(-10425 2350);
PAINT MONO (-10425 2350);
DISPLAY INVISIBLE (-10425 2350);
FORCEPROP 1 LAST PATH I125
J 0
(-10375 2500);
DISPLAY 0.978723 (-10375 2500);
PAINT WHITE (-10375 2500);
DISPLAY INVISIBLE (-10375 2500);
FORCEADD UNIVERSAL_GND..1
(-9125 1975);
FORCEPROP 3 LASTPIN (-9125 2025) SIG_NAME GND\g
J 0
(-9115 2035);
DISPLAY 0.659574 (-9115 2035);
PAINT MONO (-9115 2035);
DISPLAY INVISIBLE (-9115 2035);
FORCEPROP 2 LAST CDS_LIB pure_quanta_power
J 0
(-9125 1975);
PAINT MONO (-9125 1975);
DISPLAY INVISIBLE (-9125 1975);
FORCEPROP 1 LAST PATH I126
J 0
(-9050 1975);
DISPLAY 0.872340 (-9050 1975);
PAINT AQUA (-9050 1975);
DISPLAY INVISIBLE (-9050 1975);
FORCEPROP 1 LAST HDL_POWER GND
J 1
(-9100 1900);
DISPLAY 0.872340 (-9100 1900);
PAINT GREEN (-9100 1900);
DISPLAY INVISIBLE (-9100 1900);
FORCEADD Q_CAP..1
(-9975 2350);
FORCEPROP 1 LAST LOCATION C2158
J 0
(-9925 2450);
DISPLAY 0.489362 (-9925 2450);
PAINT SKYBLUE (-9925 2450);
FORCEPROP 2 LAST $SEC 1
J 0
(-9925 2550);
DISPLAY 0.680851 (-9925 2550);
PAINT MONO (-9925 2550);
DISPLAY INVISIBLE (-9925 2550);
FORCEPROP 2 LAST CDS_SEC 1
J 0
(-9925 2550);
DISPLAY 1.021277 (-9925 2550);
DISPLAY INVISIBLE (-9925 2550);
FORCEPROP 1 LASTPIN (-9975 2450) $PN 1
J 0
(-9965 2430);
DISPLAY 0.489362 (-9965 2430);
FORCEPROP 1 LASTPIN (-9975 2250) $PN 2
J 0
(-9965 2230);
DISPLAY 0.489362 (-9965 2230);
FORCEPROP 1 LAST MATERIAL X6S
J 0
(-9925 2250);
DISPLAY 0.489362 (-9925 2250);
PAINT SKYBLUE (-9925 2250);
FORCEPROP 1 LAST TOLERANCE 20%
J 0
(-9925 2300);
DISPLAY 0.489362 (-9925 2300);
PAINT SKYBLUE (-9925 2300);
FORCEPROP 1 LAST VALUE 22UF
J 0
(-9925 2400);
DISPLAY 0.489362 (-9925 2400);
PAINT SKYBLUE (-9925 2400);
FORCEPROP 1 LAST PART_NUMBER CH622KMEB02
J 0
(-9925 2200);
DISPLAY 0.489362 (-9925 2200);
PAINT SKYBLUE (-9925 2200);
FORCEPROP 1 LAST VOLTAGE 4V
J 0
(-9925 2350);
DISPLAY 0.489362 (-9925 2350);
PAINT SKYBLUE (-9925 2350);
FORCEPROP 1 LAST PACK_TYPE C0402
J 0
(-9925 2150);
DISPLAY 0.489362 (-9925 2150);
PAINT SKYBLUE (-9925 2150);
FORCEPROP 2 LAST CDS_LIB pure_quanta
J 0
(-9975 2350);
PAINT MONO (-9975 2350);
DISPLAY INVISIBLE (-9975 2350);
FORCEPROP 1 LAST PATH I127
J 0
(-9925 2500);
DISPLAY 0.978723 (-9925 2500);
PAINT WHITE (-9925 2500);
DISPLAY INVISIBLE (-9925 2500);
FORCEADD Q_CAP..1
(-9525 2350);
FORCEPROP 1 LAST LOCATION C2160
J 0
(-9475 2450);
DISPLAY 0.489362 (-9475 2450);
PAINT SKYBLUE (-9475 2450);
FORCEPROP 2 LAST $SEC 1
J 0
(-9475 2550);
DISPLAY 0.680851 (-9475 2550);
PAINT MONO (-9475 2550);
DISPLAY INVISIBLE (-9475 2550);
FORCEPROP 2 LAST CDS_SEC 1
J 0
(-9475 2550);
DISPLAY 1.021277 (-9475 2550);
DISPLAY INVISIBLE (-9475 2550);
FORCEPROP 1 LASTPIN (-9525 2450) $PN 1
J 0
(-9515 2430);
DISPLAY 0.489362 (-9515 2430);
FORCEPROP 1 LASTPIN (-9525 2250) $PN 2
J 0
(-9515 2230);
DISPLAY 0.489362 (-9515 2230);
FORCEPROP 1 LAST MATERIAL X6S
J 0
(-9475 2250);
DISPLAY 0.489362 (-9475 2250);
PAINT SKYBLUE (-9475 2250);
FORCEPROP 1 LAST TOLERANCE 20%
J 0
(-9475 2300);
DISPLAY 0.489362 (-9475 2300);
PAINT SKYBLUE (-9475 2300);
FORCEPROP 1 LAST VALUE 22UF
J 0
(-9475 2400);
DISPLAY 0.489362 (-9475 2400);
PAINT SKYBLUE (-9475 2400);
FORCEPROP 1 LAST PART_NUMBER CH622KMEB02
J 0
(-9475 2200);
DISPLAY 0.489362 (-9475 2200);
PAINT SKYBLUE (-9475 2200);
FORCEPROP 1 LAST VOLTAGE 4V
J 0
(-9475 2350);
DISPLAY 0.489362 (-9475 2350);
PAINT SKYBLUE (-9475 2350);
FORCEPROP 1 LAST PACK_TYPE C0402
J 0
(-9475 2150);
DISPLAY 0.489362 (-9475 2150);
PAINT SKYBLUE (-9475 2150);
FORCEPROP 2 LAST CDS_LIB pure_quanta
J 0
(-9525 2350);
PAINT MONO (-9525 2350);
DISPLAY INVISIBLE (-9525 2350);
FORCEPROP 1 LAST PATH I128
J 0
(-9475 2500);
DISPLAY 0.978723 (-9475 2500);
PAINT WHITE (-9475 2500);
DISPLAY INVISIBLE (-9475 2500);
FORCEADD Q_CAP..1
(-9125 2350);
FORCEPROP 1 LAST LOCATION C2162
J 0
(-9075 2450);
DISPLAY 0.489362 (-9075 2450);
PAINT SKYBLUE (-9075 2450);
FORCEPROP 2 LAST $SEC 1
J 0
(-9075 2550);
DISPLAY 0.680851 (-9075 2550);
PAINT MONO (-9075 2550);
DISPLAY INVISIBLE (-9075 2550);
FORCEPROP 2 LAST CDS_SEC 1
J 0
(-9075 2550);
DISPLAY 1.021277 (-9075 2550);
DISPLAY INVISIBLE (-9075 2550);
FORCEPROP 1 LASTPIN (-9125 2450) $PN 1
J 0
(-9115 2430);
DISPLAY 0.489362 (-9115 2430);
FORCEPROP 1 LASTPIN (-9125 2250) $PN 2
J 0
(-9115 2230);
DISPLAY 0.489362 (-9115 2230);
FORCEPROP 1 LAST MATERIAL X6S
J 0
(-9075 2250);
DISPLAY 0.489362 (-9075 2250);
PAINT SKYBLUE (-9075 2250);
FORCEPROP 1 LAST TOLERANCE 20%
J 0
(-9075 2300);
DISPLAY 0.489362 (-9075 2300);
PAINT SKYBLUE (-9075 2300);
FORCEPROP 1 LAST VALUE 22UF
J 0
(-9075 2400);
DISPLAY 0.489362 (-9075 2400);
PAINT SKYBLUE (-9075 2400);
FORCEPROP 1 LAST PART_NUMBER CH622KMEB02
J 0
(-9075 2200);
DISPLAY 0.489362 (-9075 2200);
PAINT SKYBLUE (-9075 2200);
FORCEPROP 1 LAST VOLTAGE 4V
J 0
(-9075 2350);
DISPLAY 0.489362 (-9075 2350);
PAINT SKYBLUE (-9075 2350);
FORCEPROP 1 LAST PACK_TYPE C0402
J 0
(-9075 2150);
DISPLAY 0.489362 (-9075 2150);
PAINT SKYBLUE (-9075 2150);
FORCEPROP 2 LAST CDS_LIB pure_quanta
J 0
(-9125 2350);
PAINT MONO (-9125 2350);
DISPLAY INVISIBLE (-9125 2350);
FORCEPROP 1 LAST PATH I129
J 0
(-9075 2500);
DISPLAY 0.978723 (-9075 2500);
PAINT WHITE (-9075 2500);
DISPLAY INVISIBLE (-9075 2500);
FORCEADD UNIVERSAL_GND..1
(-7250 3850);
FORCEPROP 3 LASTPIN (-7250 3900) SIG_NAME GND\g
J 0
(-7240 3910);
DISPLAY 0.659574 (-7240 3910);
PAINT MONO (-7240 3910);
DISPLAY INVISIBLE (-7240 3910);
FORCEPROP 2 LAST CDS_LIB pure_quanta_power
J 0
(-7250 3850);
DISPLAY INVISIBLE (-7250 3850);
FORCEPROP 1 LAST PATH I130
J 0
(-7175 3850);
DISPLAY 0.872340 (-7175 3850);
PAINT AQUA (-7175 3850);
DISPLAY INVISIBLE (-7175 3850);
FORCEPROP 1 LAST HDL_POWER GND
J 1
(-7225 3775);
DISPLAY 0.872340 (-7225 3775);
PAINT GREEN (-7225 3775);
DISPLAY INVISIBLE (-7225 3775);
FORCEADD Q_CAP..1
(-8150 4200);
FORCEPROP 1 LAST LOCATION C2163
J 0
(-8100 4300);
DISPLAY 0.489362 (-8100 4300);
PAINT SKYBLUE (-8100 4300);
FORCEPROP 2 LAST $SEC 1
J 0
(-8100 4400);
DISPLAY 0.680851 (-8100 4400);
PAINT MONO (-8100 4400);
DISPLAY INVISIBLE (-8100 4400);
FORCEPROP 2 LAST CDS_SEC 1
J 0
(-8100 4400);
DISPLAY 1.021277 (-8100 4400);
DISPLAY INVISIBLE (-8100 4400);
FORCEPROP 1 LASTPIN (-8150 4300) $PN 1
J 0
(-8140 4280);
DISPLAY 0.489362 (-8140 4280);
FORCEPROP 1 LASTPIN (-8150 4100) $PN 2
J 0
(-8140 4080);
DISPLAY 0.489362 (-8140 4080);
FORCEPROP 1 LAST MATERIAL X6S
J 0
(-8100 4100);
DISPLAY 0.489362 (-8100 4100);
PAINT SKYBLUE (-8100 4100);
FORCEPROP 1 LAST TOLERANCE 20%
J 0
(-8100 4150);
DISPLAY 0.489362 (-8100 4150);
PAINT SKYBLUE (-8100 4150);
FORCEPROP 1 LAST VALUE 22UF
J 0
(-8100 4250);
DISPLAY 0.489362 (-8100 4250);
PAINT SKYBLUE (-8100 4250);
FORCEPROP 1 LAST PART_NUMBER CH622KMEB02
J 0
(-8100 4050);
DISPLAY 0.489362 (-8100 4050);
PAINT SKYBLUE (-8100 4050);
FORCEPROP 1 LAST VOLTAGE 4V
J 0
(-8100 4200);
DISPLAY 0.489362 (-8100 4200);
PAINT SKYBLUE (-8100 4200);
FORCEPROP 1 LAST PACK_TYPE C0402
J 0
(-8100 4000);
DISPLAY 0.489362 (-8100 4000);
PAINT SKYBLUE (-8100 4000);
FORCEPROP 2 LAST CDS_LIB pure_quanta
J 0
(-8150 4200);
PAINT MONO (-8150 4200);
DISPLAY INVISIBLE (-8150 4200);
FORCEPROP 1 LAST PATH I131
J 0
(-8100 4350);
DISPLAY 0.978723 (-8100 4350);
PAINT WHITE (-8100 4350);
DISPLAY INVISIBLE (-8100 4350);
FORCEADD UNIVERSAL_POWER..1
(-8150 4475);
FORCEPROP 3 LASTPIN (-8150 4425) SIG_NAME PVDD18_S5_P0\g
J 0
(-8140 4435);
DISPLAY 0.659574 (-8140 4435);
PAINT MONO (-8140 4435);
DISPLAY INVISIBLE (-8140 4435);
FORCEPROP 1 LAST HDL_POWER PVDD18_S5_P0
J 1
(-8150 4525);
DISPLAY 0.489362 (-8150 4525);
PAINT GREEN (-8150 4525);
FORCEPROP 2 LAST CDS_LIB pure_quanta_power
J 0
(-8150 4475);
DISPLAY INVISIBLE (-8150 4475);
FORCEPROP 1 LAST PATH I132
J 0
(-8100 4500);
DISPLAY 0.872340 (-8100 4500);
PAINT AQUA (-8100 4500);
DISPLAY INVISIBLE (-8100 4500);
FORCEADD Q_CAP..1
(-7700 4200);
FORCEPROP 1 LAST LOCATION C2164
J 0
(-7650 4300);
DISPLAY 0.489362 (-7650 4300);
PAINT SKYBLUE (-7650 4300);
FORCEPROP 2 LAST $SEC 1
J 0
(-7650 4400);
DISPLAY 0.680851 (-7650 4400);
PAINT MONO (-7650 4400);
DISPLAY INVISIBLE (-7650 4400);
FORCEPROP 2 LAST CDS_SEC 1
J 0
(-7650 4400);
DISPLAY 1.021277 (-7650 4400);
DISPLAY INVISIBLE (-7650 4400);
FORCEPROP 1 LASTPIN (-7700 4300) $PN 1
J 0
(-7690 4280);
DISPLAY 0.489362 (-7690 4280);
FORCEPROP 1 LASTPIN (-7700 4100) $PN 2
J 0
(-7690 4080);
DISPLAY 0.489362 (-7690 4080);
FORCEPROP 1 LAST MATERIAL X6S
J 0
(-7650 4100);
DISPLAY 0.489362 (-7650 4100);
PAINT SKYBLUE (-7650 4100);
FORCEPROP 1 LAST TOLERANCE 20%
J 0
(-7650 4150);
DISPLAY 0.489362 (-7650 4150);
PAINT SKYBLUE (-7650 4150);
FORCEPROP 1 LAST VALUE 22UF
J 0
(-7650 4250);
DISPLAY 0.489362 (-7650 4250);
PAINT SKYBLUE (-7650 4250);
FORCEPROP 1 LAST PART_NUMBER CH622KMEB02
J 0
(-7650 4050);
DISPLAY 0.489362 (-7650 4050);
PAINT SKYBLUE (-7650 4050);
FORCEPROP 1 LAST VOLTAGE 4V
J 0
(-7650 4200);
DISPLAY 0.489362 (-7650 4200);
PAINT SKYBLUE (-7650 4200);
FORCEPROP 1 LAST PACK_TYPE C0402
J 0
(-7650 4000);
DISPLAY 0.489362 (-7650 4000);
PAINT SKYBLUE (-7650 4000);
FORCEPROP 2 LAST CDS_LIB pure_quanta
J 0
(-7700 4200);
PAINT MONO (-7700 4200);
DISPLAY INVISIBLE (-7700 4200);
FORCEPROP 1 LAST PATH I133
J 0
(-7650 4350);
DISPLAY 0.978723 (-7650 4350);
PAINT WHITE (-7650 4350);
DISPLAY INVISIBLE (-7650 4350);
FORCEADD Q_CAP..1
(-7250 4200);
FORCEPROP 1 LAST LOCATION C3897
J 0
(-7200 4300);
DISPLAY 0.489362 (-7200 4300);
PAINT SKYBLUE (-7200 4300);
FORCEPROP 2 LAST $SEC 1
J 0
(-7200 4400);
DISPLAY 0.680851 (-7200 4400);
PAINT MONO (-7200 4400);
DISPLAY INVISIBLE (-7200 4400);
FORCEPROP 2 LAST CDS_SEC 1
J 0
(-7200 4400);
DISPLAY 1.021277 (-7200 4400);
DISPLAY INVISIBLE (-7200 4400);
FORCEPROP 1 LASTPIN (-7250 4300) $PN 1
J 0
(-7240 4280);
DISPLAY 0.489362 (-7240 4280);
FORCEPROP 1 LASTPIN (-7250 4100) $PN 2
J 0
(-7240 4080);
DISPLAY 0.489362 (-7240 4080);
FORCEPROP 1 LAST MATERIAL X6S
J 0
(-7200 4100);
DISPLAY 0.489362 (-7200 4100);
PAINT SKYBLUE (-7200 4100);
FORCEPROP 1 LAST TOLERANCE 20%
J 0
(-7200 4150);
DISPLAY 0.489362 (-7200 4150);
PAINT SKYBLUE (-7200 4150);
FORCEPROP 1 LAST VALUE 22UF
J 0
(-7200 4250);
DISPLAY 0.489362 (-7200 4250);
PAINT SKYBLUE (-7200 4250);
FORCEPROP 1 LAST PART_NUMBER CH622KMEB02
J 0
(-7200 4050);
DISPLAY 0.489362 (-7200 4050);
PAINT SKYBLUE (-7200 4050);
FORCEPROP 1 LAST VOLTAGE 4V
J 0
(-7200 4200);
DISPLAY 0.489362 (-7200 4200);
PAINT SKYBLUE (-7200 4200);
FORCEPROP 1 LAST PACK_TYPE C0402
J 0
(-7200 4000);
DISPLAY 0.489362 (-7200 4000);
PAINT SKYBLUE (-7200 4000);
FORCEPROP 2 LAST CDS_LIB pure_quanta
J 0
(-7250 4200);
PAINT MONO (-7250 4200);
DISPLAY INVISIBLE (-7250 4200);
FORCEPROP 1 LAST PATH I134
J 0
(-7200 4350);
DISPLAY 0.978723 (-7200 4350);
PAINT WHITE (-7200 4350);
DISPLAY INVISIBLE (-7200 4350);
FORCEADD Q_CAP..1
(-8200 5950);
FORCEPROP 1 LAST LOCATION C2131
J 0
(-8150 6050);
DISPLAY 0.489362 (-8150 6050);
PAINT SKYBLUE (-8150 6050);
FORCEPROP 2 LAST $SEC 1
J 0
(-8150 6150);
DISPLAY 0.680851 (-8150 6150);
PAINT MONO (-8150 6150);
DISPLAY INVISIBLE (-8150 6150);
FORCEPROP 2 LAST CDS_SEC 1
J 0
(-8150 6150);
DISPLAY 1.021277 (-8150 6150);
DISPLAY INVISIBLE (-8150 6150);
FORCEPROP 1 LASTPIN (-8200 6050) $PN 1
J 0
(-8190 6030);
DISPLAY 0.489362 (-8190 6030);
FORCEPROP 1 LASTPIN (-8200 5850) $PN 2
J 0
(-8190 5830);
DISPLAY 0.489362 (-8190 5830);
FORCEPROP 1 LAST MATERIAL X6S
J 0
(-8150 5850);
DISPLAY 0.489362 (-8150 5850);
PAINT SKYBLUE (-8150 5850);
FORCEPROP 1 LAST TOLERANCE 20%
J 0
(-8150 5900);
DISPLAY 0.489362 (-8150 5900);
PAINT SKYBLUE (-8150 5900);
FORCEPROP 1 LAST VALUE 22UF
J 0
(-8150 6000);
DISPLAY 0.489362 (-8150 6000);
PAINT SKYBLUE (-8150 6000);
FORCEPROP 1 LAST PART_NUMBER CH622KMEB02
J 0
(-8150 5800);
DISPLAY 0.489362 (-8150 5800);
PAINT SKYBLUE (-8150 5800);
FORCEPROP 1 LAST VOLTAGE 4V
J 0
(-8150 5950);
DISPLAY 0.489362 (-8150 5950);
PAINT SKYBLUE (-8150 5950);
FORCEPROP 1 LAST PACK_TYPE C0402
J 0
(-8150 5750);
DISPLAY 0.489362 (-8150 5750);
PAINT SKYBLUE (-8150 5750);
FORCEPROP 2 LAST CDS_LIB pure_quanta
J 0
(-8200 5950);
PAINT MONO (-8200 5950);
DISPLAY INVISIBLE (-8200 5950);
FORCEPROP 1 LAST PATH I135
J 0
(-8150 6100);
DISPLAY 0.978723 (-8150 6100);
PAINT WHITE (-8150 6100);
DISPLAY INVISIBLE (-8150 6100);
FORCEADD Q_CAP..1
(-7750 5950);
FORCEPROP 1 LAST LOCATION C2136
J 0
(-7700 6050);
DISPLAY 0.489362 (-7700 6050);
PAINT SKYBLUE (-7700 6050);
FORCEPROP 2 LAST $SEC 1
J 0
(-7700 6150);
DISPLAY 0.680851 (-7700 6150);
PAINT MONO (-7700 6150);
DISPLAY INVISIBLE (-7700 6150);
FORCEPROP 2 LAST CDS_SEC 1
J 0
(-7700 6150);
DISPLAY 1.021277 (-7700 6150);
DISPLAY INVISIBLE (-7700 6150);
FORCEPROP 1 LASTPIN (-7750 6050) $PN 1
J 0
(-7740 6030);
DISPLAY 0.489362 (-7740 6030);
FORCEPROP 1 LASTPIN (-7750 5850) $PN 2
J 0
(-7740 5830);
DISPLAY 0.489362 (-7740 5830);
FORCEPROP 1 LAST MATERIAL X6S
J 0
(-7700 5850);
DISPLAY 0.489362 (-7700 5850);
PAINT SKYBLUE (-7700 5850);
FORCEPROP 1 LAST TOLERANCE 20%
J 0
(-7700 5900);
DISPLAY 0.489362 (-7700 5900);
PAINT SKYBLUE (-7700 5900);
FORCEPROP 1 LAST VALUE 22UF
J 0
(-7700 6000);
DISPLAY 0.489362 (-7700 6000);
PAINT SKYBLUE (-7700 6000);
FORCEPROP 1 LAST PART_NUMBER CH622KMEB02
J 0
(-7700 5800);
DISPLAY 0.489362 (-7700 5800);
PAINT SKYBLUE (-7700 5800);
FORCEPROP 1 LAST VOLTAGE 4V
J 0
(-7700 5950);
DISPLAY 0.489362 (-7700 5950);
PAINT SKYBLUE (-7700 5950);
FORCEPROP 1 LAST PACK_TYPE C0402
J 0
(-7700 5750);
DISPLAY 0.489362 (-7700 5750);
PAINT SKYBLUE (-7700 5750);
FORCEPROP 2 LAST CDS_LIB pure_quanta
J 0
(-7750 5950);
PAINT MONO (-7750 5950);
DISPLAY INVISIBLE (-7750 5950);
FORCEPROP 1 LAST PATH I136
J 0
(-7700 6100);
DISPLAY 0.978723 (-7700 6100);
PAINT WHITE (-7700 6100);
DISPLAY INVISIBLE (-7700 6100);
FORCEADD Q_CAP..1
(-7300 5950);
FORCEPROP 1 LAST LOCATION C2141
J 0
(-7250 6050);
DISPLAY 0.489362 (-7250 6050);
PAINT SKYBLUE (-7250 6050);
FORCEPROP 2 LAST $SEC 1
J 0
(-7250 6150);
DISPLAY 0.680851 (-7250 6150);
PAINT MONO (-7250 6150);
DISPLAY INVISIBLE (-7250 6150);
FORCEPROP 2 LAST CDS_SEC 1
J 0
(-7250 6150);
DISPLAY 1.021277 (-7250 6150);
DISPLAY INVISIBLE (-7250 6150);
FORCEPROP 1 LASTPIN (-7300 6050) $PN 1
J 0
(-7290 6030);
DISPLAY 0.489362 (-7290 6030);
FORCEPROP 1 LASTPIN (-7300 5850) $PN 2
J 0
(-7290 5830);
DISPLAY 0.489362 (-7290 5830);
FORCEPROP 1 LAST MATERIAL X6S
J 0
(-7250 5850);
DISPLAY 0.489362 (-7250 5850);
PAINT SKYBLUE (-7250 5850);
FORCEPROP 1 LAST TOLERANCE 20%
J 0
(-7250 5900);
DISPLAY 0.489362 (-7250 5900);
PAINT SKYBLUE (-7250 5900);
FORCEPROP 1 LAST VALUE 22UF
J 0
(-7250 6000);
DISPLAY 0.489362 (-7250 6000);
PAINT SKYBLUE (-7250 6000);
FORCEPROP 1 LAST PART_NUMBER CH622KMEB02
J 0
(-7250 5800);
DISPLAY 0.489362 (-7250 5800);
PAINT SKYBLUE (-7250 5800);
FORCEPROP 1 LAST VOLTAGE 4V
J 0
(-7250 5950);
DISPLAY 0.489362 (-7250 5950);
PAINT SKYBLUE (-7250 5950);
FORCEPROP 1 LAST PACK_TYPE C0402
J 0
(-7250 5750);
DISPLAY 0.489362 (-7250 5750);
PAINT SKYBLUE (-7250 5750);
FORCEPROP 2 LAST CDS_LIB pure_quanta
J 0
(-7300 5950);
PAINT MONO (-7300 5950);
DISPLAY INVISIBLE (-7300 5950);
FORCEPROP 1 LAST PATH I137
J 0
(-7250 6100);
DISPLAY 0.978723 (-7250 6100);
PAINT WHITE (-7250 6100);
DISPLAY INVISIBLE (-7250 6100);
FORCEADD Q_CAP..1
(-6850 5950);
FORCEPROP 1 LAST LOCATION C2145
J 0
(-6800 6050);
DISPLAY 0.489362 (-6800 6050);
PAINT SKYBLUE (-6800 6050);
FORCEPROP 2 LAST $SEC 1
J 0
(-6800 6150);
DISPLAY 0.680851 (-6800 6150);
PAINT MONO (-6800 6150);
DISPLAY INVISIBLE (-6800 6150);
FORCEPROP 2 LAST CDS_SEC 1
J 0
(-6800 6150);
DISPLAY 1.021277 (-6800 6150);
DISPLAY INVISIBLE (-6800 6150);
FORCEPROP 1 LASTPIN (-6850 6050) $PN 1
J 0
(-6840 6030);
DISPLAY 0.489362 (-6840 6030);
FORCEPROP 1 LASTPIN (-6850 5850) $PN 2
J 0
(-6840 5830);
DISPLAY 0.489362 (-6840 5830);
FORCEPROP 1 LAST MATERIAL X6S
J 0
(-6800 5850);
DISPLAY 0.489362 (-6800 5850);
PAINT SKYBLUE (-6800 5850);
FORCEPROP 1 LAST TOLERANCE 20%
J 0
(-6800 5900);
DISPLAY 0.489362 (-6800 5900);
PAINT SKYBLUE (-6800 5900);
FORCEPROP 1 LAST VALUE 22UF
J 0
(-6800 6000);
DISPLAY 0.489362 (-6800 6000);
PAINT SKYBLUE (-6800 6000);
FORCEPROP 1 LAST PART_NUMBER CH622KMEB02
J 0
(-6800 5800);
DISPLAY 0.489362 (-6800 5800);
PAINT SKYBLUE (-6800 5800);
FORCEPROP 1 LAST VOLTAGE 4V
J 0
(-6800 5950);
DISPLAY 0.489362 (-6800 5950);
PAINT SKYBLUE (-6800 5950);
FORCEPROP 1 LAST PACK_TYPE C0402
J 0
(-6800 5750);
DISPLAY 0.489362 (-6800 5750);
PAINT SKYBLUE (-6800 5750);
FORCEPROP 2 LAST CDS_LIB pure_quanta
J 0
(-6850 5950);
PAINT MONO (-6850 5950);
DISPLAY INVISIBLE (-6850 5950);
FORCEPROP 1 LAST PATH I138
J 0
(-6800 6100);
DISPLAY 0.978723 (-6800 6100);
PAINT WHITE (-6800 6100);
DISPLAY INVISIBLE (-6800 6100);
FORCEADD Q_CAP..1
(-6400 5950);
FORCEPROP 1 LAST LOCATION C2149
J 0
(-6350 6050);
DISPLAY 0.489362 (-6350 6050);
PAINT SKYBLUE (-6350 6050);
FORCEPROP 2 LAST $SEC 1
J 0
(-6350 6150);
DISPLAY 0.680851 (-6350 6150);
PAINT MONO (-6350 6150);
DISPLAY INVISIBLE (-6350 6150);
FORCEPROP 2 LAST CDS_SEC 1
J 0
(-6350 6150);
DISPLAY 1.021277 (-6350 6150);
DISPLAY INVISIBLE (-6350 6150);
FORCEPROP 1 LASTPIN (-6400 6050) $PN 1
J 0
(-6390 6030);
DISPLAY 0.489362 (-6390 6030);
FORCEPROP 1 LASTPIN (-6400 5850) $PN 2
J 0
(-6390 5830);
DISPLAY 0.489362 (-6390 5830);
FORCEPROP 1 LAST MATERIAL X6S
J 0
(-6350 5850);
DISPLAY 0.489362 (-6350 5850);
PAINT SKYBLUE (-6350 5850);
FORCEPROP 1 LAST TOLERANCE 20%
J 0
(-6350 5900);
DISPLAY 0.489362 (-6350 5900);
PAINT SKYBLUE (-6350 5900);
FORCEPROP 1 LAST VALUE 22UF
J 0
(-6350 6000);
DISPLAY 0.489362 (-6350 6000);
PAINT SKYBLUE (-6350 6000);
FORCEPROP 1 LAST PART_NUMBER CH622KMEB02
J 0
(-6350 5800);
DISPLAY 0.489362 (-6350 5800);
PAINT SKYBLUE (-6350 5800);
FORCEPROP 1 LAST VOLTAGE 4V
J 0
(-6350 5950);
DISPLAY 0.489362 (-6350 5950);
PAINT SKYBLUE (-6350 5950);
FORCEPROP 1 LAST PACK_TYPE C0402
J 0
(-6350 5750);
DISPLAY 0.489362 (-6350 5750);
PAINT SKYBLUE (-6350 5750);
FORCEPROP 2 LAST CDS_LIB pure_quanta
J 0
(-6400 5950);
PAINT MONO (-6400 5950);
DISPLAY INVISIBLE (-6400 5950);
FORCEPROP 1 LAST PATH I139
J 0
(-6350 6100);
DISPLAY 0.978723 (-6350 6100);
PAINT WHITE (-6350 6100);
DISPLAY INVISIBLE (-6350 6100);
FORCEADD UNIVERSAL_POWER..1
(-8200 6225);
FORCEPROP 3 LASTPIN (-8200 6175) SIG_NAME PVDDIO_P0\g
J 0
(-8190 6185);
DISPLAY 0.659574 (-8190 6185);
PAINT MONO (-8190 6185);
DISPLAY INVISIBLE (-8190 6185);
FORCEPROP 1 LAST HDL_POWER PVDDIO_P0
J 1
(-8200 6275);
DISPLAY 0.489362 (-8200 6275);
PAINT GREEN (-8200 6275);
FORCEPROP 2 LAST CDS_LIB pure_quanta_power
J 0
(-8200 6225);
DISPLAY INVISIBLE (-8200 6225);
FORCEPROP 1 LAST PATH I140
J 0
(-8150 6250);
DISPLAY 0.872340 (-8150 6250);
PAINT AQUA (-8150 6250);
DISPLAY INVISIBLE (-8150 6250);
FORCEADD Q_CAP..1
(-5950 5950);
FORCEPROP 1 LAST LOCATION C3898
J 0
(-5900 6050);
DISPLAY 0.489362 (-5900 6050);
PAINT SKYBLUE (-5900 6050);
FORCEPROP 2 LAST $SEC 1
J 0
(-5900 6150);
DISPLAY 0.680851 (-5900 6150);
PAINT MONO (-5900 6150);
DISPLAY INVISIBLE (-5900 6150);
FORCEPROP 2 LAST CDS_SEC 1
J 0
(-5900 6150);
DISPLAY 1.021277 (-5900 6150);
DISPLAY INVISIBLE (-5900 6150);
FORCEPROP 1 LASTPIN (-5950 6050) $PN 1
J 0
(-5940 6030);
DISPLAY 0.489362 (-5940 6030);
FORCEPROP 1 LASTPIN (-5950 5850) $PN 2
J 0
(-5940 5830);
DISPLAY 0.489362 (-5940 5830);
FORCEPROP 1 LAST MATERIAL X6S
J 0
(-5900 5850);
DISPLAY 0.489362 (-5900 5850);
PAINT SKYBLUE (-5900 5850);
FORCEPROP 1 LAST TOLERANCE 20%
J 0
(-5900 5900);
DISPLAY 0.489362 (-5900 5900);
PAINT SKYBLUE (-5900 5900);
FORCEPROP 1 LAST VALUE 22UF
J 0
(-5900 6000);
DISPLAY 0.489362 (-5900 6000);
PAINT SKYBLUE (-5900 6000);
FORCEPROP 1 LAST PART_NUMBER CH622KMEB02
J 0
(-5900 5800);
DISPLAY 0.489362 (-5900 5800);
PAINT SKYBLUE (-5900 5800);
FORCEPROP 1 LAST VOLTAGE 4V
J 0
(-5900 5950);
DISPLAY 0.489362 (-5900 5950);
PAINT SKYBLUE (-5900 5950);
FORCEPROP 1 LAST PACK_TYPE C0402
J 0
(-5900 5750);
DISPLAY 0.489362 (-5900 5750);
PAINT SKYBLUE (-5900 5750);
FORCEPROP 2 LAST CDS_LIB pure_quanta
J 0
(-5950 5950);
PAINT MONO (-5950 5950);
DISPLAY INVISIBLE (-5950 5950);
FORCEPROP 1 LAST PATH I141
J 0
(-5900 6100);
DISPLAY 0.978723 (-5900 6100);
PAINT WHITE (-5900 6100);
DISPLAY INVISIBLE (-5900 6100);
FORCEADD UNIVERSAL_GND..1
(-5500 5600);
FORCEPROP 3 LASTPIN (-5500 5650) SIG_NAME GND\g
J 0
(-5490 5660);
DISPLAY 0.659574 (-5490 5660);
PAINT MONO (-5490 5660);
DISPLAY INVISIBLE (-5490 5660);
FORCEPROP 2 LAST CDS_LIB pure_quanta_power
J 0
(-5500 5600);
PAINT MONO (-5500 5600);
DISPLAY INVISIBLE (-5500 5600);
FORCEPROP 1 LAST PATH I142
J 0
(-5425 5600);
DISPLAY 0.872340 (-5425 5600);
PAINT AQUA (-5425 5600);
DISPLAY INVISIBLE (-5425 5600);
FORCEPROP 1 LAST HDL_POWER GND
J 1
(-5475 5525);
DISPLAY 0.872340 (-5475 5525);
PAINT GREEN (-5475 5525);
DISPLAY INVISIBLE (-5475 5525);
FORCEADD Q_CAP..1
(-5500 5950);
FORCEPROP 1 LAST LOCATION C3899
J 0
(-5450 6050);
DISPLAY 0.489362 (-5450 6050);
PAINT SKYBLUE (-5450 6050);
FORCEPROP 2 LAST $SEC 1
J 0
(-5450 6150);
DISPLAY 0.680851 (-5450 6150);
PAINT MONO (-5450 6150);
DISPLAY INVISIBLE (-5450 6150);
FORCEPROP 2 LAST CDS_SEC 1
J 0
(-5450 6150);
DISPLAY 1.021277 (-5450 6150);
DISPLAY INVISIBLE (-5450 6150);
FORCEPROP 1 LASTPIN (-5500 6050) $PN 1
J 0
(-5490 6030);
DISPLAY 0.489362 (-5490 6030);
FORCEPROP 1 LASTPIN (-5500 5850) $PN 2
J 0
(-5490 5830);
DISPLAY 0.489362 (-5490 5830);
FORCEPROP 1 LAST MATERIAL X6S
J 0
(-5450 5850);
DISPLAY 0.489362 (-5450 5850);
PAINT SKYBLUE (-5450 5850);
FORCEPROP 1 LAST TOLERANCE 20%
J 0
(-5450 5900);
DISPLAY 0.489362 (-5450 5900);
PAINT SKYBLUE (-5450 5900);
FORCEPROP 1 LAST VALUE 22UF
J 0
(-5450 6000);
DISPLAY 0.489362 (-5450 6000);
PAINT SKYBLUE (-5450 6000);
FORCEPROP 1 LAST PART_NUMBER CH622KMEB02
J 0
(-5450 5800);
DISPLAY 0.489362 (-5450 5800);
PAINT SKYBLUE (-5450 5800);
FORCEPROP 1 LAST VOLTAGE 4V
J 0
(-5450 5950);
DISPLAY 0.489362 (-5450 5950);
PAINT SKYBLUE (-5450 5950);
FORCEPROP 1 LAST PACK_TYPE C0402
J 0
(-5450 5750);
DISPLAY 0.489362 (-5450 5750);
PAINT SKYBLUE (-5450 5750);
FORCEPROP 2 LAST CDS_LIB pure_quanta
J 0
(-5500 5950);
PAINT MONO (-5500 5950);
DISPLAY INVISIBLE (-5500 5950);
FORCEPROP 1 LAST PATH I143
J 0
(-5450 6100);
DISPLAY 0.978723 (-5450 6100);
PAINT WHITE (-5450 6100);
DISPLAY INVISIBLE (-5450 6100);
FORCEADD UNIVERSAL_GND..1
(-12700 3900);
FORCEPROP 3 LASTPIN (-12700 3950) SIG_NAME GND\g
J 0
(-12690 3960);
DISPLAY 0.659574 (-12690 3960);
PAINT MONO (-12690 3960);
DISPLAY INVISIBLE (-12690 3960);
FORCEPROP 2 LAST CDS_LIB pure_quanta_power
J 0
(-12700 3900);
PAINT MONO (-12700 3900);
DISPLAY INVISIBLE (-12700 3900);
FORCEPROP 1 LAST PATH I82
J 0
(-12625 3900);
DISPLAY 0.872340 (-12625 3900);
PAINT AQUA (-12625 3900);
DISPLAY INVISIBLE (-12625 3900);
FORCEPROP 1 LAST HDL_POWER GND
J 1
(-12675 3825);
DISPLAY 0.872340 (-12675 3825);
PAINT GREEN (-12675 3825);
DISPLAY INVISIBLE (-12675 3825);
FORCEADD Q_CAP..1
(-13100 4275);
FORCEPROP 1 LAST LOCATION C3888
J 0
(-13050 4375);
DISPLAY 0.489362 (-13050 4375);
PAINT SKYBLUE (-13050 4375);
FORCEPROP 2 LAST $SEC 1
J 0
(-13050 4475);
DISPLAY 0.680851 (-13050 4475);
PAINT MONO (-13050 4475);
DISPLAY INVISIBLE (-13050 4475);
FORCEPROP 2 LAST CDS_SEC 1
J 0
(-13050 4475);
DISPLAY 1.021277 (-13050 4475);
DISPLAY INVISIBLE (-13050 4475);
FORCEPROP 1 LASTPIN (-13100 4375) $PN 1
J 0
(-13090 4355);
DISPLAY 0.489362 (-13090 4355);
FORCEPROP 1 LASTPIN (-13100 4175) $PN 2
J 0
(-13090 4155);
DISPLAY 0.489362 (-13090 4155);
FORCEPROP 1 LAST MATERIAL X6S
J 0
(-13050 4175);
DISPLAY 0.489362 (-13050 4175);
PAINT SKYBLUE (-13050 4175);
FORCEPROP 1 LAST TOLERANCE 20%
J 0
(-13050 4225);
DISPLAY 0.489362 (-13050 4225);
PAINT SKYBLUE (-13050 4225);
FORCEPROP 1 LAST VALUE 22UF
J 0
(-13050 4325);
DISPLAY 0.489362 (-13050 4325);
PAINT SKYBLUE (-13050 4325);
FORCEPROP 1 LAST PART_NUMBER CH622KMEB02
J 0
(-13050 4125);
DISPLAY 0.489362 (-13050 4125);
PAINT SKYBLUE (-13050 4125);
FORCEPROP 1 LAST VOLTAGE 4V
J 0
(-13050 4275);
DISPLAY 0.489362 (-13050 4275);
PAINT SKYBLUE (-13050 4275);
FORCEPROP 1 LAST PACK_TYPE C0402
J 0
(-13050 4075);
DISPLAY 0.489362 (-13050 4075);
PAINT SKYBLUE (-13050 4075);
FORCEPROP 2 LAST CDS_LIB pure_quanta
J 0
(-13100 4275);
PAINT MONO (-13100 4275);
DISPLAY INVISIBLE (-13100 4275);
FORCEPROP 1 LAST PATH I83
J 0
(-13050 4425);
DISPLAY 0.978723 (-13050 4425);
PAINT WHITE (-13050 4425);
DISPLAY INVISIBLE (-13050 4425);
FORCEADD UNIVERSAL_POWER..1
(-13100 4550);
FORCEPROP 3 LASTPIN (-13100 4500) SIG_NAME PVDDCR_SOC_P0\g
J 0
(-13090 4510);
DISPLAY 0.659574 (-13090 4510);
PAINT MONO (-13090 4510);
DISPLAY INVISIBLE (-13090 4510);
FORCEPROP 1 LAST HDL_POWER PVDDCR_SOC_P0
J 1
(-13100 4600);
DISPLAY 0.489362 (-13100 4600);
PAINT GREEN (-13100 4600);
FORCEPROP 2 LAST CDS_LIB pure_quanta_power
J 0
(-13100 4550);
DISPLAY INVISIBLE (-13100 4550);
FORCEPROP 1 LAST PATH I84
J 0
(-13050 4575);
DISPLAY 0.872340 (-13050 4575);
PAINT AQUA (-13050 4575);
DISPLAY INVISIBLE (-13050 4575);
FORCEADD Q_CAP..1
(-13125 5050);
FORCEPROP 1 LAST LOCATION C2130
J 0
(-13075 5150);
DISPLAY 0.489362 (-13075 5150);
PAINT SKYBLUE (-13075 5150);
FORCEPROP 2 LAST $SEC 1
J 0
(-13075 5250);
DISPLAY 0.680851 (-13075 5250);
PAINT MONO (-13075 5250);
DISPLAY INVISIBLE (-13075 5250);
FORCEPROP 2 LAST CDS_SEC 1
J 0
(-13075 5250);
DISPLAY 1.021277 (-13075 5250);
DISPLAY INVISIBLE (-13075 5250);
FORCEPROP 1 LASTPIN (-13125 5150) $PN 1
J 0
(-13115 5130);
DISPLAY 0.489362 (-13115 5130);
FORCEPROP 1 LASTPIN (-13125 4950) $PN 2
J 0
(-13115 4930);
DISPLAY 0.489362 (-13115 4930);
FORCEPROP 1 LAST MATERIAL X6S
J 0
(-13075 4950);
DISPLAY 0.489362 (-13075 4950);
PAINT SKYBLUE (-13075 4950);
FORCEPROP 1 LAST TOLERANCE 20%
J 0
(-13075 5000);
DISPLAY 0.489362 (-13075 5000);
PAINT SKYBLUE (-13075 5000);
FORCEPROP 1 LAST VALUE 22UF
J 0
(-13075 5100);
DISPLAY 0.489362 (-13075 5100);
PAINT SKYBLUE (-13075 5100);
FORCEPROP 1 LAST PART_NUMBER CH622KMEB02
J 0
(-13075 4900);
DISPLAY 0.489362 (-13075 4900);
PAINT SKYBLUE (-13075 4900);
FORCEPROP 1 LAST VOLTAGE 4V
J 0
(-13075 5050);
DISPLAY 0.489362 (-13075 5050);
PAINT SKYBLUE (-13075 5050);
FORCEPROP 1 LAST PACK_TYPE C0402
J 0
(-13075 4850);
DISPLAY 0.489362 (-13075 4850);
PAINT SKYBLUE (-13075 4850);
FORCEPROP 2 LAST CDS_LIB pure_quanta
J 0
(-13125 5050);
PAINT MONO (-13125 5050);
DISPLAY INVISIBLE (-13125 5050);
FORCEPROP 1 LAST PATH I85
J 0
(-13075 5200);
DISPLAY 0.978723 (-13075 5200);
PAINT WHITE (-13075 5200);
DISPLAY INVISIBLE (-13075 5200);
FORCEADD Q_CAP..1
(-12700 4275);
FORCEPROP 1 LAST LOCATION C3889
J 0
(-12650 4375);
DISPLAY 0.489362 (-12650 4375);
PAINT SKYBLUE (-12650 4375);
FORCEPROP 2 LAST $SEC 1
J 0
(-12650 4475);
DISPLAY 0.680851 (-12650 4475);
PAINT MONO (-12650 4475);
DISPLAY INVISIBLE (-12650 4475);
FORCEPROP 2 LAST CDS_SEC 1
J 0
(-12650 4475);
DISPLAY 1.021277 (-12650 4475);
DISPLAY INVISIBLE (-12650 4475);
FORCEPROP 1 LASTPIN (-12700 4375) $PN 1
J 0
(-12690 4355);
DISPLAY 0.489362 (-12690 4355);
FORCEPROP 1 LASTPIN (-12700 4175) $PN 2
J 0
(-12690 4155);
DISPLAY 0.489362 (-12690 4155);
FORCEPROP 1 LAST MATERIAL X6S
J 0
(-12650 4175);
DISPLAY 0.489362 (-12650 4175);
PAINT SKYBLUE (-12650 4175);
FORCEPROP 1 LAST TOLERANCE 20%
J 0
(-12650 4225);
DISPLAY 0.489362 (-12650 4225);
PAINT SKYBLUE (-12650 4225);
FORCEPROP 1 LAST VALUE 22UF
J 0
(-12650 4325);
DISPLAY 0.489362 (-12650 4325);
PAINT SKYBLUE (-12650 4325);
FORCEPROP 1 LAST PART_NUMBER CH622KMEB02
J 0
(-12650 4125);
DISPLAY 0.489362 (-12650 4125);
PAINT SKYBLUE (-12650 4125);
FORCEPROP 1 LAST VOLTAGE 4V
J 0
(-12650 4275);
DISPLAY 0.489362 (-12650 4275);
PAINT SKYBLUE (-12650 4275);
FORCEPROP 1 LAST PACK_TYPE C0402
J 0
(-12650 4075);
DISPLAY 0.489362 (-12650 4075);
PAINT SKYBLUE (-12650 4075);
FORCEPROP 2 LAST CDS_LIB pure_quanta
J 0
(-12700 4275);
PAINT MONO (-12700 4275);
DISPLAY INVISIBLE (-12700 4275);
FORCEPROP 1 LAST PATH I86
J 0
(-12650 4425);
DISPLAY 0.978723 (-12650 4425);
PAINT WHITE (-12650 4425);
DISPLAY INVISIBLE (-12650 4425);
FORCEADD Q_CAP..1
(-12675 5050);
FORCEPROP 1 LAST LOCATION C2135
J 0
(-12625 5150);
DISPLAY 0.489362 (-12625 5150);
PAINT SKYBLUE (-12625 5150);
FORCEPROP 2 LAST $SEC 1
J 0
(-12625 5250);
DISPLAY 0.680851 (-12625 5250);
PAINT MONO (-12625 5250);
DISPLAY INVISIBLE (-12625 5250);
FORCEPROP 2 LAST CDS_SEC 1
J 0
(-12625 5250);
DISPLAY 1.021277 (-12625 5250);
DISPLAY INVISIBLE (-12625 5250);
FORCEPROP 1 LASTPIN (-12675 5150) $PN 1
J 0
(-12665 5130);
DISPLAY 0.489362 (-12665 5130);
FORCEPROP 1 LASTPIN (-12675 4950) $PN 2
J 0
(-12665 4930);
DISPLAY 0.489362 (-12665 4930);
FORCEPROP 1 LAST MATERIAL X6S
J 0
(-12625 4950);
DISPLAY 0.489362 (-12625 4950);
PAINT SKYBLUE (-12625 4950);
FORCEPROP 1 LAST TOLERANCE 20%
J 0
(-12625 5000);
DISPLAY 0.489362 (-12625 5000);
PAINT SKYBLUE (-12625 5000);
FORCEPROP 1 LAST VALUE 22UF
J 0
(-12625 5100);
DISPLAY 0.489362 (-12625 5100);
PAINT SKYBLUE (-12625 5100);
FORCEPROP 1 LAST PART_NUMBER CH622KMEB02
J 0
(-12625 4900);
DISPLAY 0.489362 (-12625 4900);
PAINT SKYBLUE (-12625 4900);
FORCEPROP 1 LAST VOLTAGE 4V
J 0
(-12625 5050);
DISPLAY 0.489362 (-12625 5050);
PAINT SKYBLUE (-12625 5050);
FORCEPROP 1 LAST PACK_TYPE C0402
J 0
(-12625 4850);
DISPLAY 0.489362 (-12625 4850);
PAINT SKYBLUE (-12625 4850);
FORCEPROP 2 LAST CDS_LIB pure_quanta
J 0
(-12675 5050);
PAINT MONO (-12675 5050);
DISPLAY INVISIBLE (-12675 5050);
FORCEPROP 1 LAST PATH I87
J 0
(-12625 5200);
DISPLAY 0.978723 (-12625 5200);
PAINT WHITE (-12625 5200);
DISPLAY INVISIBLE (-12625 5200);
FORCEADD UNIVERSAL_POWER..1
(-13125 5325);
FORCEPROP 3 LASTPIN (-13125 5275) SIG_NAME PVDDCR_SOC_P0\g
J 0
(-13115 5285);
DISPLAY 0.659574 (-13115 5285);
PAINT MONO (-13115 5285);
DISPLAY INVISIBLE (-13115 5285);
FORCEPROP 1 LAST HDL_POWER PVDDCR_SOC_P0
J 1
(-13125 5375);
DISPLAY 0.489362 (-13125 5375);
PAINT GREEN (-13125 5375);
FORCEPROP 2 LAST CDS_LIB pure_quanta_power
J 0
(-13125 5325);
DISPLAY INVISIBLE (-13125 5325);
FORCEPROP 1 LAST PATH I88
J 0
(-13075 5350);
DISPLAY 0.872340 (-13075 5350);
PAINT AQUA (-13075 5350);
DISPLAY INVISIBLE (-13075 5350);
FORCEADD Q_CAP..1
(-13125 5850);
FORCEPROP 1 LAST LOCATION C2129
J 0
(-13075 5950);
DISPLAY 0.489362 (-13075 5950);
PAINT SKYBLUE (-13075 5950);
FORCEPROP 2 LAST $SEC 1
J 0
(-13075 6050);
DISPLAY 0.680851 (-13075 6050);
PAINT MONO (-13075 6050);
DISPLAY INVISIBLE (-13075 6050);
FORCEPROP 2 LAST CDS_SEC 1
J 0
(-13075 6050);
DISPLAY 1.021277 (-13075 6050);
DISPLAY INVISIBLE (-13075 6050);
FORCEPROP 1 LASTPIN (-13125 5950) $PN 1
J 0
(-13115 5930);
DISPLAY 0.489362 (-13115 5930);
FORCEPROP 1 LASTPIN (-13125 5750) $PN 2
J 0
(-13115 5730);
DISPLAY 0.489362 (-13115 5730);
FORCEPROP 1 LAST MATERIAL X6S
J 0
(-13075 5750);
DISPLAY 0.489362 (-13075 5750);
PAINT SKYBLUE (-13075 5750);
FORCEPROP 1 LAST TOLERANCE 20%
J 0
(-13075 5800);
DISPLAY 0.489362 (-13075 5800);
PAINT SKYBLUE (-13075 5800);
FORCEPROP 1 LAST VALUE 22UF
J 0
(-13075 5900);
DISPLAY 0.489362 (-13075 5900);
PAINT SKYBLUE (-13075 5900);
FORCEPROP 1 LAST PART_NUMBER CH622KMEB02
J 0
(-13075 5700);
DISPLAY 0.489362 (-13075 5700);
PAINT SKYBLUE (-13075 5700);
FORCEPROP 1 LAST VOLTAGE 4V
J 0
(-13075 5850);
DISPLAY 0.489362 (-13075 5850);
PAINT SKYBLUE (-13075 5850);
FORCEPROP 1 LAST PACK_TYPE C0402
J 0
(-13075 5650);
DISPLAY 0.489362 (-13075 5650);
PAINT SKYBLUE (-13075 5650);
FORCEPROP 2 LAST CDS_LIB pure_quanta
J 0
(-13125 5850);
PAINT MONO (-13125 5850);
DISPLAY INVISIBLE (-13125 5850);
FORCEPROP 1 LAST PATH I89
J 0
(-13075 6000);
DISPLAY 0.978723 (-13075 6000);
PAINT WHITE (-13075 6000);
DISPLAY INVISIBLE (-13075 6000);
FORCEADD Q_CAP..1
(-12675 5850);
FORCEPROP 1 LAST LOCATION C2134
J 0
(-12625 5950);
DISPLAY 0.489362 (-12625 5950);
PAINT SKYBLUE (-12625 5950);
FORCEPROP 2 LAST $SEC 1
J 0
(-12625 6050);
DISPLAY 0.680851 (-12625 6050);
PAINT MONO (-12625 6050);
DISPLAY INVISIBLE (-12625 6050);
FORCEPROP 2 LAST CDS_SEC 1
J 0
(-12625 6050);
DISPLAY 1.021277 (-12625 6050);
DISPLAY INVISIBLE (-12625 6050);
FORCEPROP 1 LASTPIN (-12675 5950) $PN 1
J 0
(-12665 5930);
DISPLAY 0.489362 (-12665 5930);
FORCEPROP 1 LASTPIN (-12675 5750) $PN 2
J 0
(-12665 5730);
DISPLAY 0.489362 (-12665 5730);
FORCEPROP 1 LAST MATERIAL X6S
J 0
(-12625 5750);
DISPLAY 0.489362 (-12625 5750);
PAINT SKYBLUE (-12625 5750);
FORCEPROP 1 LAST TOLERANCE 20%
J 0
(-12625 5800);
DISPLAY 0.489362 (-12625 5800);
PAINT SKYBLUE (-12625 5800);
FORCEPROP 1 LAST VALUE 22UF
J 0
(-12625 5900);
DISPLAY 0.489362 (-12625 5900);
PAINT SKYBLUE (-12625 5900);
FORCEPROP 1 LAST PART_NUMBER CH622KMEB02
J 0
(-12625 5700);
DISPLAY 0.489362 (-12625 5700);
PAINT SKYBLUE (-12625 5700);
FORCEPROP 1 LAST VOLTAGE 4V
J 0
(-12625 5850);
DISPLAY 0.489362 (-12625 5850);
PAINT SKYBLUE (-12625 5850);
FORCEPROP 1 LAST PACK_TYPE C0402
J 0
(-12625 5650);
DISPLAY 0.489362 (-12625 5650);
PAINT SKYBLUE (-12625 5650);
FORCEPROP 2 LAST CDS_LIB pure_quanta
J 0
(-12675 5850);
PAINT MONO (-12675 5850);
DISPLAY INVISIBLE (-12675 5850);
FORCEPROP 1 LAST PATH I90
J 0
(-12625 6000);
DISPLAY 0.978723 (-12625 6000);
PAINT WHITE (-12625 6000);
DISPLAY INVISIBLE (-12625 6000);
FORCEADD UNIVERSAL_POWER..1
(-13125 6125);
FORCEPROP 3 LASTPIN (-13125 6075) SIG_NAME PVDDCR_SOC_P0\g
J 0
(-13115 6085);
DISPLAY 0.659574 (-13115 6085);
PAINT MONO (-13115 6085);
DISPLAY INVISIBLE (-13115 6085);
FORCEPROP 1 LAST HDL_POWER PVDDCR_SOC_P0
J 1
(-13125 6175);
DISPLAY 0.489362 (-13125 6175);
PAINT GREEN (-13125 6175);
FORCEPROP 2 LAST CDS_LIB pure_quanta_power
J 0
(-13125 6125);
DISPLAY INVISIBLE (-13125 6125);
FORCEPROP 1 LAST PATH I91
J 0
(-13075 6150);
DISPLAY 0.872340 (-13075 6150);
PAINT AQUA (-13075 6150);
DISPLAY INVISIBLE (-13075 6150);
FORCEADD Q_CAP..1
(-12225 5050);
FORCEPROP 1 LAST LOCATION C2140
J 0
(-12175 5150);
DISPLAY 0.489362 (-12175 5150);
PAINT SKYBLUE (-12175 5150);
FORCEPROP 2 LAST $SEC 1
J 0
(-12175 5250);
DISPLAY 0.680851 (-12175 5250);
PAINT MONO (-12175 5250);
DISPLAY INVISIBLE (-12175 5250);
FORCEPROP 2 LAST CDS_SEC 1
J 0
(-12175 5250);
DISPLAY 1.021277 (-12175 5250);
DISPLAY INVISIBLE (-12175 5250);
FORCEPROP 1 LASTPIN (-12225 5150) $PN 1
J 0
(-12215 5130);
DISPLAY 0.489362 (-12215 5130);
FORCEPROP 1 LASTPIN (-12225 4950) $PN 2
J 0
(-12215 4930);
DISPLAY 0.489362 (-12215 4930);
FORCEPROP 1 LAST MATERIAL X6S
J 0
(-12175 4950);
DISPLAY 0.489362 (-12175 4950);
PAINT SKYBLUE (-12175 4950);
FORCEPROP 1 LAST TOLERANCE 20%
J 0
(-12175 5000);
DISPLAY 0.489362 (-12175 5000);
PAINT SKYBLUE (-12175 5000);
FORCEPROP 1 LAST VALUE 22UF
J 0
(-12175 5100);
DISPLAY 0.489362 (-12175 5100);
PAINT SKYBLUE (-12175 5100);
FORCEPROP 1 LAST PART_NUMBER CH622KMEB02
J 0
(-12175 4900);
DISPLAY 0.489362 (-12175 4900);
PAINT SKYBLUE (-12175 4900);
FORCEPROP 1 LAST VOLTAGE 4V
J 0
(-12175 5050);
DISPLAY 0.489362 (-12175 5050);
PAINT SKYBLUE (-12175 5050);
FORCEPROP 1 LAST PACK_TYPE C0402
J 0
(-12175 4850);
DISPLAY 0.489362 (-12175 4850);
PAINT SKYBLUE (-12175 4850);
FORCEPROP 2 LAST CDS_LIB pure_quanta
J 0
(-12225 5050);
PAINT MONO (-12225 5050);
DISPLAY INVISIBLE (-12225 5050);
FORCEPROP 1 LAST PATH I92
J 0
(-12175 5200);
DISPLAY 0.978723 (-12175 5200);
PAINT WHITE (-12175 5200);
DISPLAY INVISIBLE (-12175 5200);
FORCEADD Q_CAP..1
(-11775 5050);
FORCEPROP 1 LAST LOCATION C2144
J 0
(-11725 5150);
DISPLAY 0.489362 (-11725 5150);
PAINT SKYBLUE (-11725 5150);
FORCEPROP 2 LAST $SEC 1
J 0
(-11725 5250);
DISPLAY 0.680851 (-11725 5250);
PAINT MONO (-11725 5250);
DISPLAY INVISIBLE (-11725 5250);
FORCEPROP 2 LAST CDS_SEC 1
J 0
(-11725 5250);
DISPLAY 1.021277 (-11725 5250);
DISPLAY INVISIBLE (-11725 5250);
FORCEPROP 1 LASTPIN (-11775 5150) $PN 1
J 0
(-11765 5130);
DISPLAY 0.489362 (-11765 5130);
FORCEPROP 1 LASTPIN (-11775 4950) $PN 2
J 0
(-11765 4930);
DISPLAY 0.489362 (-11765 4930);
FORCEPROP 1 LAST MATERIAL X6S
J 0
(-11725 4950);
DISPLAY 0.489362 (-11725 4950);
PAINT SKYBLUE (-11725 4950);
FORCEPROP 1 LAST TOLERANCE 20%
J 0
(-11725 5000);
DISPLAY 0.489362 (-11725 5000);
PAINT SKYBLUE (-11725 5000);
FORCEPROP 1 LAST VALUE 22UF
J 0
(-11725 5100);
DISPLAY 0.489362 (-11725 5100);
PAINT SKYBLUE (-11725 5100);
FORCEPROP 1 LAST PART_NUMBER CH622KMEB02
J 0
(-11725 4900);
DISPLAY 0.489362 (-11725 4900);
PAINT SKYBLUE (-11725 4900);
FORCEPROP 1 LAST VOLTAGE 4V
J 0
(-11725 5050);
DISPLAY 0.489362 (-11725 5050);
PAINT SKYBLUE (-11725 5050);
FORCEPROP 1 LAST PACK_TYPE C0402
J 0
(-11725 4850);
DISPLAY 0.489362 (-11725 4850);
PAINT SKYBLUE (-11725 4850);
FORCEPROP 2 LAST CDS_LIB pure_quanta
J 0
(-11775 5050);
PAINT MONO (-11775 5050);
DISPLAY INVISIBLE (-11775 5050);
FORCEPROP 1 LAST PATH I93
J 0
(-11725 5200);
DISPLAY 0.978723 (-11725 5200);
PAINT WHITE (-11725 5200);
DISPLAY INVISIBLE (-11725 5200);
FORCEADD Q_CAP..1
(-11325 5050);
FORCEPROP 1 LAST LOCATION C2148
J 0
(-11275 5150);
DISPLAY 0.489362 (-11275 5150);
PAINT SKYBLUE (-11275 5150);
FORCEPROP 2 LAST $SEC 1
J 0
(-11275 5250);
DISPLAY 0.680851 (-11275 5250);
PAINT MONO (-11275 5250);
DISPLAY INVISIBLE (-11275 5250);
FORCEPROP 2 LAST CDS_SEC 1
J 0
(-11275 5250);
DISPLAY 1.021277 (-11275 5250);
DISPLAY INVISIBLE (-11275 5250);
FORCEPROP 1 LASTPIN (-11325 5150) $PN 1
J 0
(-11315 5130);
DISPLAY 0.489362 (-11315 5130);
FORCEPROP 1 LASTPIN (-11325 4950) $PN 2
J 0
(-11315 4930);
DISPLAY 0.489362 (-11315 4930);
FORCEPROP 1 LAST MATERIAL X6S
J 0
(-11275 4950);
DISPLAY 0.489362 (-11275 4950);
PAINT SKYBLUE (-11275 4950);
FORCEPROP 1 LAST TOLERANCE 20%
J 0
(-11275 5000);
DISPLAY 0.489362 (-11275 5000);
PAINT SKYBLUE (-11275 5000);
FORCEPROP 1 LAST VALUE 22UF
J 0
(-11275 5100);
DISPLAY 0.489362 (-11275 5100);
PAINT SKYBLUE (-11275 5100);
FORCEPROP 1 LAST PART_NUMBER CH622KMEB02
J 0
(-11275 4900);
DISPLAY 0.489362 (-11275 4900);
PAINT SKYBLUE (-11275 4900);
FORCEPROP 1 LAST VOLTAGE 4V
J 0
(-11275 5050);
DISPLAY 0.489362 (-11275 5050);
PAINT SKYBLUE (-11275 5050);
FORCEPROP 1 LAST PACK_TYPE C0402
J 0
(-11275 4850);
DISPLAY 0.489362 (-11275 4850);
PAINT SKYBLUE (-11275 4850);
FORCEPROP 2 LAST CDS_LIB pure_quanta
J 0
(-11325 5050);
PAINT MONO (-11325 5050);
DISPLAY INVISIBLE (-11325 5050);
FORCEPROP 1 LAST PATH I94
J 0
(-11275 5200);
DISPLAY 0.978723 (-11275 5200);
PAINT WHITE (-11275 5200);
DISPLAY INVISIBLE (-11275 5200);
FORCEADD Q_CAP..1
(-12225 5850);
FORCEPROP 1 LAST LOCATION C2139
J 0
(-12175 5950);
DISPLAY 0.489362 (-12175 5950);
PAINT SKYBLUE (-12175 5950);
FORCEPROP 2 LAST $SEC 1
J 0
(-12175 6050);
DISPLAY 0.680851 (-12175 6050);
PAINT MONO (-12175 6050);
DISPLAY INVISIBLE (-12175 6050);
FORCEPROP 2 LAST CDS_SEC 1
J 0
(-12175 6050);
DISPLAY 1.021277 (-12175 6050);
DISPLAY INVISIBLE (-12175 6050);
FORCEPROP 1 LASTPIN (-12225 5950) $PN 1
J 0
(-12215 5930);
DISPLAY 0.489362 (-12215 5930);
FORCEPROP 1 LASTPIN (-12225 5750) $PN 2
J 0
(-12215 5730);
DISPLAY 0.489362 (-12215 5730);
FORCEPROP 1 LAST MATERIAL X6S
J 0
(-12175 5750);
DISPLAY 0.489362 (-12175 5750);
PAINT SKYBLUE (-12175 5750);
FORCEPROP 1 LAST TOLERANCE 20%
J 0
(-12175 5800);
DISPLAY 0.489362 (-12175 5800);
PAINT SKYBLUE (-12175 5800);
FORCEPROP 1 LAST VALUE 22UF
J 0
(-12175 5900);
DISPLAY 0.489362 (-12175 5900);
PAINT SKYBLUE (-12175 5900);
FORCEPROP 1 LAST PART_NUMBER CH622KMEB02
J 0
(-12175 5700);
DISPLAY 0.489362 (-12175 5700);
PAINT SKYBLUE (-12175 5700);
FORCEPROP 1 LAST VOLTAGE 4V
J 0
(-12175 5850);
DISPLAY 0.489362 (-12175 5850);
PAINT SKYBLUE (-12175 5850);
FORCEPROP 1 LAST PACK_TYPE C0402
J 0
(-12175 5650);
DISPLAY 0.489362 (-12175 5650);
PAINT SKYBLUE (-12175 5650);
FORCEPROP 2 LAST CDS_LIB pure_quanta
J 0
(-12225 5850);
PAINT MONO (-12225 5850);
DISPLAY INVISIBLE (-12225 5850);
FORCEPROP 1 LAST PATH I95
J 0
(-12175 6000);
DISPLAY 0.978723 (-12175 6000);
PAINT WHITE (-12175 6000);
DISPLAY INVISIBLE (-12175 6000);
FORCEADD Q_CAP..1
(-11775 5850);
FORCEPROP 1 LAST LOCATION C2143
J 0
(-11725 5950);
DISPLAY 0.489362 (-11725 5950);
PAINT SKYBLUE (-11725 5950);
FORCEPROP 2 LAST $SEC 1
J 0
(-11725 6050);
DISPLAY 0.680851 (-11725 6050);
PAINT MONO (-11725 6050);
DISPLAY INVISIBLE (-11725 6050);
FORCEPROP 2 LAST CDS_SEC 1
J 0
(-11725 6050);
DISPLAY 1.021277 (-11725 6050);
DISPLAY INVISIBLE (-11725 6050);
FORCEPROP 1 LASTPIN (-11775 5950) $PN 1
J 0
(-11765 5930);
DISPLAY 0.489362 (-11765 5930);
FORCEPROP 1 LASTPIN (-11775 5750) $PN 2
J 0
(-11765 5730);
DISPLAY 0.489362 (-11765 5730);
FORCEPROP 1 LAST MATERIAL X6S
J 0
(-11725 5750);
DISPLAY 0.489362 (-11725 5750);
PAINT SKYBLUE (-11725 5750);
FORCEPROP 1 LAST TOLERANCE 20%
J 0
(-11725 5800);
DISPLAY 0.489362 (-11725 5800);
PAINT SKYBLUE (-11725 5800);
FORCEPROP 1 LAST VALUE 22UF
J 0
(-11725 5900);
DISPLAY 0.489362 (-11725 5900);
PAINT SKYBLUE (-11725 5900);
FORCEPROP 1 LAST PART_NUMBER CH622KMEB02
J 0
(-11725 5700);
DISPLAY 0.489362 (-11725 5700);
PAINT SKYBLUE (-11725 5700);
FORCEPROP 1 LAST VOLTAGE 4V
J 0
(-11725 5850);
DISPLAY 0.489362 (-11725 5850);
PAINT SKYBLUE (-11725 5850);
FORCEPROP 1 LAST PACK_TYPE C0402
J 0
(-11725 5650);
DISPLAY 0.489362 (-11725 5650);
PAINT SKYBLUE (-11725 5650);
FORCEPROP 2 LAST CDS_LIB pure_quanta
J 0
(-11775 5850);
PAINT MONO (-11775 5850);
DISPLAY INVISIBLE (-11775 5850);
FORCEPROP 1 LAST PATH I96
J 0
(-11725 6000);
DISPLAY 0.978723 (-11725 6000);
PAINT WHITE (-11725 6000);
DISPLAY INVISIBLE (-11725 6000);
FORCEADD Q_CAP..1
(-10875 5050);
FORCEPROP 1 LAST LOCATION C2152
J 0
(-10825 5150);
DISPLAY 0.489362 (-10825 5150);
PAINT SKYBLUE (-10825 5150);
FORCEPROP 2 LAST $SEC 1
J 0
(-10825 5250);
DISPLAY 0.680851 (-10825 5250);
PAINT MONO (-10825 5250);
DISPLAY INVISIBLE (-10825 5250);
FORCEPROP 2 LAST CDS_SEC 1
J 0
(-10825 5250);
DISPLAY 1.021277 (-10825 5250);
DISPLAY INVISIBLE (-10825 5250);
FORCEPROP 1 LASTPIN (-10875 5150) $PN 1
J 0
(-10865 5130);
DISPLAY 0.489362 (-10865 5130);
FORCEPROP 1 LASTPIN (-10875 4950) $PN 2
J 0
(-10865 4930);
DISPLAY 0.489362 (-10865 4930);
FORCEPROP 1 LAST MATERIAL X6S
J 0
(-10825 4950);
DISPLAY 0.489362 (-10825 4950);
PAINT SKYBLUE (-10825 4950);
FORCEPROP 1 LAST TOLERANCE 20%
J 0
(-10825 5000);
DISPLAY 0.489362 (-10825 5000);
PAINT SKYBLUE (-10825 5000);
FORCEPROP 1 LAST VALUE 22UF
J 0
(-10825 5100);
DISPLAY 0.489362 (-10825 5100);
PAINT SKYBLUE (-10825 5100);
FORCEPROP 1 LAST PART_NUMBER CH622KMEB02
J 0
(-10825 4900);
DISPLAY 0.489362 (-10825 4900);
PAINT SKYBLUE (-10825 4900);
FORCEPROP 1 LAST VOLTAGE 4V
J 0
(-10825 5050);
DISPLAY 0.489362 (-10825 5050);
PAINT SKYBLUE (-10825 5050);
FORCEPROP 1 LAST PACK_TYPE C0402
J 0
(-10825 4850);
DISPLAY 0.489362 (-10825 4850);
PAINT SKYBLUE (-10825 4850);
FORCEPROP 2 LAST CDS_LIB pure_quanta
J 0
(-10875 5050);
PAINT MONO (-10875 5050);
DISPLAY INVISIBLE (-10875 5050);
FORCEPROP 1 LAST PATH I97
J 0
(-10825 5200);
DISPLAY 0.978723 (-10825 5200);
PAINT WHITE (-10825 5200);
DISPLAY INVISIBLE (-10825 5200);
FORCEADD Q_CAP..1
(-10425 5050);
FORCEPROP 1 LAST LOCATION C2155
J 0
(-10375 5150);
DISPLAY 0.489362 (-10375 5150);
PAINT SKYBLUE (-10375 5150);
FORCEPROP 2 LAST $SEC 1
J 0
(-10375 5250);
DISPLAY 0.680851 (-10375 5250);
PAINT MONO (-10375 5250);
DISPLAY INVISIBLE (-10375 5250);
FORCEPROP 2 LAST CDS_SEC 1
J 0
(-10375 5250);
DISPLAY 1.021277 (-10375 5250);
DISPLAY INVISIBLE (-10375 5250);
FORCEPROP 1 LASTPIN (-10425 5150) $PN 1
J 0
(-10415 5130);
DISPLAY 0.489362 (-10415 5130);
FORCEPROP 1 LASTPIN (-10425 4950) $PN 2
J 0
(-10415 4930);
DISPLAY 0.489362 (-10415 4930);
FORCEPROP 1 LAST MATERIAL X6S
J 0
(-10375 4950);
DISPLAY 0.489362 (-10375 4950);
PAINT SKYBLUE (-10375 4950);
FORCEPROP 1 LAST TOLERANCE 20%
J 0
(-10375 5000);
DISPLAY 0.489362 (-10375 5000);
PAINT SKYBLUE (-10375 5000);
FORCEPROP 1 LAST VALUE 22UF
J 0
(-10375 5100);
DISPLAY 0.489362 (-10375 5100);
PAINT SKYBLUE (-10375 5100);
FORCEPROP 1 LAST PART_NUMBER CH622KMEB02
J 0
(-10375 4900);
DISPLAY 0.489362 (-10375 4900);
PAINT SKYBLUE (-10375 4900);
FORCEPROP 1 LAST VOLTAGE 4V
J 0
(-10375 5050);
DISPLAY 0.489362 (-10375 5050);
PAINT SKYBLUE (-10375 5050);
FORCEPROP 1 LAST PACK_TYPE C0402
J 0
(-10375 4850);
DISPLAY 0.489362 (-10375 4850);
PAINT SKYBLUE (-10375 4850);
FORCEPROP 2 LAST CDS_LIB pure_quanta
J 0
(-10425 5050);
PAINT MONO (-10425 5050);
DISPLAY INVISIBLE (-10425 5050);
FORCEPROP 1 LAST PATH I98
J 0
(-10375 5200);
DISPLAY 0.978723 (-10375 5200);
PAINT WHITE (-10375 5200);
DISPLAY INVISIBLE (-10375 5200);
FORCEADD Q_CAP..1
(-10875 5850);
FORCEPROP 1 LAST LOCATION C2151
J 0
(-10825 5950);
DISPLAY 0.489362 (-10825 5950);
PAINT SKYBLUE (-10825 5950);
FORCEPROP 2 LAST $SEC 1
J 0
(-10825 6050);
DISPLAY 0.680851 (-10825 6050);
PAINT MONO (-10825 6050);
DISPLAY INVISIBLE (-10825 6050);
FORCEPROP 2 LAST CDS_SEC 1
J 0
(-10825 6050);
DISPLAY 1.021277 (-10825 6050);
DISPLAY INVISIBLE (-10825 6050);
FORCEPROP 1 LASTPIN (-10875 5950) $PN 1
J 0
(-10865 5930);
DISPLAY 0.489362 (-10865 5930);
FORCEPROP 1 LASTPIN (-10875 5750) $PN 2
J 0
(-10865 5730);
DISPLAY 0.489362 (-10865 5730);
FORCEPROP 1 LAST MATERIAL X6S
J 0
(-10825 5750);
DISPLAY 0.489362 (-10825 5750);
PAINT SKYBLUE (-10825 5750);
FORCEPROP 1 LAST TOLERANCE 20%
J 0
(-10825 5800);
DISPLAY 0.489362 (-10825 5800);
PAINT SKYBLUE (-10825 5800);
FORCEPROP 1 LAST VALUE 22UF
J 0
(-10825 5900);
DISPLAY 0.489362 (-10825 5900);
PAINT SKYBLUE (-10825 5900);
FORCEPROP 1 LAST PART_NUMBER CH622KMEB02
J 0
(-10825 5700);
DISPLAY 0.489362 (-10825 5700);
PAINT SKYBLUE (-10825 5700);
FORCEPROP 1 LAST VOLTAGE 4V
J 0
(-10825 5850);
DISPLAY 0.489362 (-10825 5850);
PAINT SKYBLUE (-10825 5850);
FORCEPROP 1 LAST PACK_TYPE C0402
J 0
(-10825 5650);
DISPLAY 0.489362 (-10825 5650);
PAINT SKYBLUE (-10825 5650);
FORCEPROP 2 LAST CDS_LIB pure_quanta
J 0
(-10875 5850);
PAINT MONO (-10875 5850);
DISPLAY INVISIBLE (-10875 5850);
FORCEPROP 1 LAST PATH I99
J 0
(-10825 6000);
DISPLAY 0.978723 (-10825 6000);
PAINT WHITE (-10825 6000);
DISPLAY INVISIBLE (-10825 6000);
FORCEADD QUANTA_TITLE_BLOCK_C..1
(-4275 325);
FORCEPROP 0 LAST CDS_CON_LAST_MODIFIED Fri Mar 11 14:52:44 2022
J 0
(-6160 340);
DISPLAY INVISIBLE (-6160 340);
FORCEPROP 1 LAST CUSTOM_TXT_CDS <CON_LAST_MODIFIED>
J 0
(-6160 340);
DISPLAY 0.978723 (-6160 340);
FORCEPROP 2 LAST CUSTOM_TXT_CDS <XR_PAGE_TITLE>
J 0
(-12165 5575);
DISPLAY 0.638298 (-12165 5575);
PAINT PINK (-12165 5575);
DISPLAY INVISIBLE (-12165 5575);
FORCEPROP 1 LAST CUSTOM_TXT_CDS <NAME_2>
J 0
(-7450 375);
FORCEPROP 1 LAST CUSTOM_TXT_CDS <NAME_1>
J 0
(-7450 500);
FORCEPROP 1 LAST CUSTOM_TXT_CDS <Q_NUMBER>
J 0
(-5678 428);
DISPLAY 1.212766 (-5678 428);
FORCEPROP 1 LAST CUSTOM_TXT_CDS <Q_PROJ>
J 0
(-6657 427);
DISPLAY 1.212766 (-6657 427);
FORCEPROP 1 LAST CUSTOM_TXT_CDS <Q_REV>
J 0
(-4459 428);
DISPLAY 1.212766 (-4459 428);
FORCEPROP 1 LAST CUSTOM_TXT_CDS <CON_PAGE_NUM> OF <CON_TOTAL_PAGES>
J 0
(-4721 343);
DISPLAY 0.978723 (-4721 343);
FORCEPROP 1 LAST Q_DEPT BU9
J 1
(-8038 374);
DISPLAY 1.957447 (-8038 374);
PAINT GREEN (-8038 374);
FORCEPROP 1 LAST Q_TITLE CPU0 CAVITY TOP DECOUPLING CAPS
J 0
(-13550 400);
DISPLAY 2.446809 (-13550 400);
PAINT GREEN (-13550 400);
FORCEPROP 2 LAST PAGE_BORDER TRUE
J 0
(-12165 5575);
DISPLAY 0.638298 (-12165 5575);
PAINT PINK (-12165 5575);
DISPLAY INVISIBLE (-12165 5575);
FORCEPROP 1 LAST CDS_LMAN_SYM_OUTLINE -9475,6775,100,-125
J 0
(-4275 325);
DISPLAY 0.468085 (-4275 325);
PAINT GREEN (-4275 325);
DISPLAY INVISIBLE (-4275 325);
FORCEPROP 2 LAST CDS_LIB pure_quanta
J 0
(-4275 325);
DISPLAY INVISIBLE (-4275 325);
FORCEPROP 1 LAST COMMENT_BODY TRUE
J 0
(-4263 312);
DISPLAY 0.978723 (-4263 312);
PAINT GREEN (-4263 312);
DISPLAY INVISIBLE (-4263 312);
FORCEPROP 2 LAST CDS_XR_PAGE_TITLE CR-67 : @T6G_MB_LIB.T6G(SCH_1):PAGE67
J 0
(-12165 5575);
DISPLAY 0.638298 (-12165 5575);
PAINT PINK (-12165 5575);
DISPLAY INVISIBLE (-12165 5575);
WIRE 16 -1 (-12675 1775)(-13125 1775);
WIRE 16 -1 (-12225 1775)(-12675 1775);
WIRE 16 -1 (-12675 1700)(-12675 1775);
WIRE 16 -1 (-13125 1775)(-13125 1825);
WIRE 16 -1 (-13125 1775)(-13125 1700);
WIRE 16 -1 (-11775 1775)(-12225 1775);
WIRE 16 -1 (-12225 1700)(-12225 1775);
WIRE 16 -1 (-11325 1775)(-11775 1775);
WIRE 16 -1 (-11775 1700)(-11775 1775);
WIRE 16 -1 (-10875 1775)(-11325 1775);
WIRE 16 -1 (-11325 1775)(-11325 1700);
WIRE 16 -1 (-10875 1700)(-10875 1775);
WIRE 16 -1 (-12675 1375)(-13125 1375);
WIRE 16 -1 (-12225 1375)(-12675 1375);
WIRE 16 -1 (-12675 1375)(-12675 1500);
WIRE 16 -1 (-13125 1375)(-13125 1500);
WIRE 16 -1 (-11775 1375)(-12225 1375);
WIRE 16 -1 (-12225 1375)(-12225 1500);
WIRE 16 -1 (-11325 1375)(-11775 1375);
WIRE 16 -1 (-11775 1375)(-11775 1500);
WIRE 16 -1 (-10875 1375)(-11325 1375);
WIRE 16 -1 (-11325 1375)(-11325 1500);
WIRE 16 -1 (-10875 1375)(-10875 1500);
WIRE 16 -1 (-10875 1275)(-10875 1375);
WIRE 16 -1 (-9125 2450)(-9125 2525);
WIRE 16 -1 (-9125 2525)(-9525 2525);
WIRE 16 -1 (-9525 2525)(-9525 2450);
WIRE 16 -1 (-9525 2525)(-9975 2525);
WIRE 16 -1 (-9975 2450)(-9975 2525);
WIRE 16 -1 (-9975 2525)(-10425 2525);
WIRE 16 -1 (-10425 2450)(-10425 2525);
WIRE 16 -1 (-10425 2525)(-10875 2525);
WIRE 16 -1 (-10875 2525)(-10875 2450);
WIRE 16 -1 (-10875 2525)(-11325 2525);
WIRE 16 -1 (-11325 2450)(-11325 2525);
WIRE 16 -1 (-11325 2525)(-11775 2525);
WIRE 16 -1 (-11775 2450)(-11775 2525);
WIRE 16 -1 (-11775 2525)(-12225 2525);
WIRE 16 -1 (-12225 2525)(-12225 2450);
WIRE 16 -1 (-12225 2525)(-12675 2525);
WIRE 16 -1 (-12675 2525)(-13125 2525);
WIRE 16 -1 (-12675 2450)(-12675 2525);
WIRE 16 -1 (-13125 2525)(-13125 2575);
WIRE 16 -1 (-13125 2525)(-13125 2450);
WIRE 16 -1 (-12675 2125)(-13125 2125);
WIRE 16 -1 (-12225 2125)(-12675 2125);
WIRE 16 -1 (-12675 2125)(-12675 2250);
WIRE 16 -1 (-13125 2125)(-13125 2250);
WIRE 16 -1 (-11775 2125)(-12225 2125);
WIRE 16 -1 (-12225 2125)(-12225 2250);
WIRE 16 -1 (-11325 2125)(-11775 2125);
WIRE 16 -1 (-11775 2125)(-11775 2250);
WIRE 16 -1 (-10875 2125)(-11325 2125);
WIRE 16 -1 (-11325 2125)(-11325 2250);
WIRE 16 -1 (-10425 2125)(-10875 2125);
WIRE 16 -1 (-10875 2125)(-10875 2250);
WIRE 16 -1 (-9975 2125)(-10425 2125);
WIRE 16 -1 (-10425 2125)(-10425 2250);
WIRE 16 -1 (-9525 2125)(-9975 2125);
WIRE 16 -1 (-9975 2125)(-9975 2250);
WIRE 16 -1 (-9125 2125)(-9525 2125);
WIRE 16 -1 (-9525 2125)(-9525 2250);
WIRE 16 -1 (-9125 2025)(-9125 2125);
WIRE 16 -1 (-9125 2125)(-9125 2250);
WIRE 16 -1 (-13100 4050)(-13100 4175);
WIRE 16 -1 (-12700 4050)(-13100 4050);
WIRE 16 -1 (-12700 4050)(-12700 4175);
WIRE 16 -1 (-12700 3950)(-12700 4050);
WIRE 16 -1 (-12675 4825)(-13125 4825);
WIRE 16 -1 (-12225 4825)(-12675 4825);
WIRE 16 -1 (-12675 4825)(-12675 4950);
WIRE 16 -1 (-13125 4825)(-13125 4950);
WIRE 16 -1 (-11775 4825)(-12225 4825);
WIRE 16 -1 (-12225 4825)(-12225 4950);
WIRE 16 -1 (-11325 4825)(-11775 4825);
WIRE 16 -1 (-11775 4825)(-11775 4950);
WIRE 16 -1 (-10875 4825)(-11325 4825);
WIRE 16 -1 (-11325 4825)(-11325 4950);
WIRE 16 -1 (-10425 4825)(-10875 4825);
WIRE 16 -1 (-10875 4825)(-10875 4950);
WIRE 16 -1 (-9975 4825)(-10425 4825);
WIRE 16 -1 (-10425 4825)(-10425 4950);
WIRE 16 -1 (-9525 4825)(-9975 4825);
WIRE 16 -1 (-9975 4825)(-9975 4950);
WIRE 16 -1 (-9125 4825)(-9525 4825);
WIRE 16 -1 (-9525 4825)(-9525 4950);
WIRE 16 -1 (-9125 4825)(-9125 4950);
WIRE 16 -1 (-9125 4725)(-9125 4825);
WIRE 16 -1 (-12700 4450)(-13100 4450);
WIRE 16 -1 (-12700 4375)(-12700 4450);
WIRE 16 -1 (-13100 4450)(-13100 4500);
WIRE 16 -1 (-13100 4450)(-13100 4375);
WIRE 16 -1 (-9125 5950)(-9125 6025);
WIRE 16 -1 (-9125 6025)(-9525 6025);
WIRE 16 -1 (-9525 6025)(-9525 5950);
WIRE 16 -1 (-9525 6025)(-9975 6025);
WIRE 16 -1 (-9975 5950)(-9975 6025);
WIRE 16 -1 (-9975 6025)(-10425 6025);
WIRE 16 -1 (-10425 5950)(-10425 6025);
WIRE 16 -1 (-10425 6025)(-10875 6025);
WIRE 16 -1 (-10875 6025)(-10875 5950);
WIRE 16 -1 (-10875 6025)(-11325 6025);
WIRE 16 -1 (-11325 5950)(-11325 6025);
WIRE 16 -1 (-11325 6025)(-11775 6025);
WIRE 16 -1 (-11775 5950)(-11775 6025);
WIRE 16 -1 (-11775 6025)(-12225 6025);
WIRE 16 -1 (-12225 6025)(-12225 5950);
WIRE 16 -1 (-12225 6025)(-12675 6025);
WIRE 16 -1 (-12675 6025)(-13125 6025);
WIRE 16 -1 (-12675 5950)(-12675 6025);
WIRE 16 -1 (-13125 6025)(-13125 6075);
WIRE 16 -1 (-13125 6025)(-13125 5950);
WIRE 16 -1 (-12675 5625)(-13125 5625);
WIRE 16 -1 (-12225 5625)(-12675 5625);
WIRE 16 -1 (-12675 5625)(-12675 5750);
WIRE 16 -1 (-13125 5625)(-13125 5750);
WIRE 16 -1 (-11775 5625)(-12225 5625);
WIRE 16 -1 (-12225 5625)(-12225 5750);
WIRE 16 -1 (-11775 5625)(-11775 5750);
WIRE 16 -1 (-11325 5625)(-11775 5625);
WIRE 16 -1 (-10875 5625)(-11325 5625);
WIRE 16 -1 (-11325 5625)(-11325 5750);
WIRE 16 -1 (-10425 5625)(-10875 5625);
WIRE 16 -1 (-10875 5625)(-10875 5750);
WIRE 16 -1 (-9975 5625)(-10425 5625);
WIRE 16 -1 (-10425 5625)(-10425 5750);
WIRE 16 -1 (-9525 5625)(-9975 5625);
WIRE 16 -1 (-9975 5625)(-9975 5750);
WIRE 16 -1 (-9125 5625)(-9525 5625);
WIRE 16 -1 (-9525 5625)(-9525 5750);
WIRE 16 -1 (-9125 5625)(-9125 5750);
WIRE 16 -1 (-9125 5525)(-9125 5625);
WIRE 16 -1 (-9125 5150)(-9125 5225);
WIRE 16 -1 (-9125 5225)(-9525 5225);
WIRE 16 -1 (-9525 5225)(-9525 5150);
WIRE 16 -1 (-9525 5225)(-9975 5225);
WIRE 16 -1 (-9975 5150)(-9975 5225);
WIRE 16 -1 (-9975 5225)(-10425 5225);
WIRE 16 -1 (-10425 5150)(-10425 5225);
WIRE 16 -1 (-10425 5225)(-10875 5225);
WIRE 16 -1 (-10875 5225)(-10875 5150);
WIRE 16 -1 (-10875 5225)(-11325 5225);
WIRE 16 -1 (-11325 5150)(-11325 5225);
WIRE 16 -1 (-11325 5225)(-11775 5225);
WIRE 16 -1 (-11775 5150)(-11775 5225);
WIRE 16 -1 (-11775 5225)(-12225 5225);
WIRE 16 -1 (-12225 5225)(-12225 5150);
WIRE 16 -1 (-12225 5225)(-12675 5225);
WIRE 16 -1 (-12675 5225)(-13125 5225);
WIRE 16 -1 (-12675 5150)(-12675 5225);
WIRE 16 -1 (-13125 5225)(-13125 5275);
WIRE 16 -1 (-13125 5225)(-13125 5150);
WIRE 16 3135 (-13400 1150)(-8725 1150);
WIRE 16 3135 (-13400 1150)(-13400 3025);
WIRE 16 3135 (-8725 1150)(-8725 3025);
WIRE 16 3135 (-13400 3025)(-8725 3025);
WIRE 16 3135 (-13400 3675)(-8725 3675);
WIRE 16 3135 (-13400 3675)(-13400 6700);
WIRE 16 3135 (-8725 3675)(-8725 6700);
WIRE 16 3135 (-13400 6700)(-8725 6700);
WIRE 16 -1 (-7750 6125)(-8200 6125);
WIRE 16 -1 (-7300 6125)(-7750 6125);
WIRE 16 -1 (-7750 6050)(-7750 6125);
WIRE 16 -1 (-8200 6125)(-8200 6175);
WIRE 16 -1 (-8200 6125)(-8200 6050);
WIRE 16 -1 (-6850 6125)(-7300 6125);
WIRE 16 -1 (-7300 6125)(-7300 6050);
WIRE 16 -1 (-6400 6125)(-6850 6125);
WIRE 16 -1 (-6850 6050)(-6850 6125);
WIRE 16 -1 (-5950 6125)(-6400 6125);
WIRE 16 -1 (-6400 6050)(-6400 6125);
WIRE 16 -1 (-5500 6125)(-5950 6125);
WIRE 16 -1 (-5950 6050)(-5950 6125);
WIRE 16 -1 (-5500 6050)(-5500 6125);
WIRE 16 -1 (-7750 5725)(-8200 5725);
WIRE 16 -1 (-7300 5725)(-7750 5725);
WIRE 16 -1 (-7750 5725)(-7750 5850);
WIRE 16 -1 (-8200 5725)(-8200 5850);
WIRE 16 -1 (-6850 5725)(-7300 5725);
WIRE 16 -1 (-7300 5725)(-7300 5850);
WIRE 16 -1 (-6400 5725)(-6850 5725);
WIRE 16 -1 (-6850 5725)(-6850 5850);
WIRE 16 -1 (-5950 5725)(-6400 5725);
WIRE 16 -1 (-6400 5725)(-6400 5850);
WIRE 16 -1 (-5500 5725)(-5950 5725);
WIRE 16 -1 (-5950 5725)(-5950 5850);
WIRE 16 -1 (-5500 5650)(-5500 5725);
WIRE 16 -1 (-5500 5725)(-5500 5850);
WIRE 16 3135 (-8475 5450)(-4725 5450);
WIRE 16 3135 (-8475 5450)(-8475 6700);
WIRE 16 3135 (-4725 5450)(-4725 6700);
WIRE 16 3135 (-8475 6700)(-4725 6700);
WIRE 16 3135 (-8450 3725)(-4525 3725);
WIRE 16 3135 (-8450 3725)(-8450 5000);
WIRE 16 3135 (-8450 5000)(-4525 5000);
WIRE 16 -1 (-7250 3900)(-7250 3975);
WIRE 16 -1 (-7250 4100)(-7250 3975);
WIRE 16 -1 (-7250 3975)(-7700 3975);
WIRE 16 -1 (-7700 4100)(-7700 3975);
WIRE 16 -1 (-7700 3975)(-8150 3975);
WIRE 16 -1 (-8150 3975)(-8150 4100);
WIRE 16 3135 (-4475 3725)(-4475 5000);
WIRE 16 -1 (-7700 4375)(-8150 4375);
WIRE 16 -1 (-7250 4375)(-7700 4375);
WIRE 16 -1 (-7700 4300)(-7700 4375);
WIRE 16 -1 (-8150 4375)(-8150 4425);
WIRE 16 -1 (-8150 4375)(-8150 4300);
WIRE 16 -1 (-7250 4300)(-7250 4375);
DOT 1 (-12700 4050);
DOT 1 (-9525 2125);
DOT 1 (-10875 4825);
DOT 1 (-13100 4450);
DOT 1 (-12675 4825);
DOT 1 (-13125 5225);
DOT 1 (-13125 6025);
DOT 1 (-12675 5225);
DOT 1 (-12675 5625);
DOT 1 (-12675 6025);
DOT 1 (-12225 4825);
DOT 1 (-11325 4825);
DOT 1 (-12225 5225);
DOT 1 (-11775 5225);
DOT 1 (-12225 5625);
DOT 1 (-12225 6025);
DOT 1 (-11775 5625);
DOT 1 (-11775 6025);
DOT 1 (-11325 5225);
DOT 1 (-11325 5625);
DOT 1 (-11325 6025);
DOT 1 (-10425 4825);
DOT 1 (-10875 5225);
DOT 1 (-10875 5625);
DOT 1 (-10875 6025);
DOT 1 (-10425 5225);
DOT 1 (-10425 5625);
DOT 1 (-10425 6025);
DOT 1 (-9975 4825);
DOT 1 (-9525 4825);
DOT 1 (-9975 5225);
DOT 1 (-9975 5625);
DOT 1 (-9975 6025);
DOT 1 (-9525 5225);
DOT 1 (-9525 5625);
DOT 1 (-9525 6025);
DOT 1 (-9125 4825);
DOT 1 (-9125 5625);
DOT 1 (-13125 1775);
DOT 1 (-12675 1375);
DOT 1 (-12675 1775);
DOT 1 (-13125 2525);
DOT 1 (-12675 2125);
DOT 1 (-12675 2525);
DOT 1 (-12225 1375);
DOT 1 (-12225 1775);
DOT 1 (-11775 1775);
DOT 1 (-11775 1375);
DOT 1 (-11325 1375);
DOT 1 (-11325 1775);
DOT 1 (-10875 1375);
DOT 1 (-12225 2125);
DOT 1 (-12225 2525);
DOT 1 (-11775 2125);
DOT 1 (-11775 2525);
DOT 1 (-11325 2125);
DOT 1 (-11325 2525);
DOT 1 (-10875 2125);
DOT 1 (-10425 2125);
DOT 1 (-9975 2125);
DOT 1 (-9525 2525);
DOT 1 (-9125 2125);
DOT 1 (-9975 2525);
DOT 1 (-10425 2525);
DOT 1 (-10875 2525);
DOT 1 (-7700 3975);
DOT 1 (-7250 3975);
DOT 1 (-8150 4375);
DOT 1 (-7700 4375);
DOT 1 (-8200 6125);
DOT 1 (-7750 5725);
DOT 1 (-7750 6125);
DOT 1 (-7300 5725);
DOT 1 (-7300 6125);
DOT 1 (-6850 5725);
DOT 1 (-6850 6125);
DOT 1 (-6400 5725);
DOT 1 (-6400 6125);
DOT 1 (-5950 5725);
DOT 1 (-5950 6125);
DOT 1 (-5500 5725);
DOT 1 (-11775 4825);
FORCENOTE
PVDD11_S3_P0: 16PCS 22UF ON TOP
(-13150 2850) 0;
DISPLAY LEFT (-13150 2850);
DISPLAY 2.510638 (-13150 2850);
PAINT WHITE (-13150 2850);
FORCENOTE
PVDD18_S5_P0: 3PCS 22UF ON TOP
(-8225 4675) 0;
DISPLAY LEFT (-8225 4675);
DISPLAY 2.510638 (-8225 4675);
PAINT WHITE (-8225 4675);
FORCENOTE
PVDDIO_P0: 7PCS 22UF ON TOP
(-8225 6450) 0;
DISPLAY LEFT (-8225 6450);
DISPLAY 2.510638 (-8225 6450);
PAINT WHITE (-8225 6450);
FORCENOTE
PVDDCR_SOC_P0: 22PCS 22UF ON TOP
(-13150 6400) 0;
DISPLAY LEFT (-13150 6400);
DISPLAY 2.510638 (-13150 6400);
PAINT WHITE (-13150 6400);
FORCENOTE
5
(-11350 5325) 0;
DISPLAY LEFT (-11350 5325);
DISPLAY 1.021277 (-11350 5325);
PAINT SKYBLUE (-11350 5325);
FORCENOTE
5
(-11350 6125) 0;
DISPLAY LEFT (-11350 6125);
DISPLAY 1.021277 (-11350 6125);
PAINT SKYBLUE (-11350 6125);
FORCENOTE
10
(-9175 5325) 0;
DISPLAY LEFT (-9175 5325);
DISPLAY 1.021277 (-9175 5325);
PAINT SKYBLUE (-9175 5325);
FORCENOTE
10
(-9175 6125) 0;
DISPLAY LEFT (-9175 6125);
DISPLAY 1.021277 (-9175 6125);
PAINT SKYBLUE (-9175 6125);
FORCENOTE
5
(-11350 1875) 0;
DISPLAY LEFT (-11350 1875);
DISPLAY 1.021277 (-11350 1875);
PAINT SKYBLUE (-11350 1875);
FORCENOTE
5
(-11350 2625) 0;
DISPLAY LEFT (-11350 2625);
DISPLAY 1.021277 (-11350 2625);
PAINT SKYBLUE (-11350 2625);
FORCENOTE
10
(-9175 2625) 0;
DISPLAY LEFT (-9175 2625);
DISPLAY 1.021277 (-9175 2625);
PAINT SKYBLUE (-9175 2625);
FORCENOTE
5
(-6425 6225) 0;
DISPLAY LEFT (-6425 6225);
DISPLAY 1.021277 (-6425 6225);
PAINT SKYBLUE (-6425 6225);
QUIT
